FILE_TYPE = MACRO_DRAWING;
SET COLOR_WIRE YELLOW;
SET COLOR_PROP MONO;
SET COLOR_DOT WHITE;
SET COLOR_ARC YELLOW;
SET COLOR_BODY GREEN;
SET COLOR_NOTE MONO;
SET PROP_DISPLAY VALUE;
SET PAGE_NUMBER P108;
FORCEADD CAP_A..1
(-3275 675);
FORCEPROP 1 LAST PACK_TYPE 0402V
J 0
(-3225 475);
DISPLAY 0.617021 (-3225 475);
PAINT SKYBLUE (-3225 475);
FORCEPROP 1 LASTPIN (-3275 575) $PN 2
J 0
(-3265 555);
DISPLAY 0.617021 (-3265 555);
PAINT ORANGE (-3265 555);
FORCEPROP 1 LAST MATERIAL X7R
J 0
(-3225 575);
DISPLAY 0.617021 (-3225 575);
PAINT SKYBLUE (-3225 575);
FORCEPROP 1 LAST VOLTAGE 16V
J 0
(-3225 675);
DISPLAY 0.617021 (-3225 675);
PAINT SKYBLUE (-3225 675);
FORCEPROP 1 LAST TOLERANCE 10%
J 0
(-3225 625);
DISPLAY 0.617021 (-3225 625);
PAINT SKYBLUE (-3225 625);
FORCEPROP 1 LAST VALUE 0.1UF
J 0
(-3225 725);
DISPLAY 0.617021 (-3225 725);
PAINT SKYBLUE (-3225 725);
FORCEPROP 1 LASTPIN (-3275 775) $PN 1
J 0
(-3265 755);
DISPLAY 0.617021 (-3265 755);
PAINT ORANGE (-3265 755);
FORCEPROP 1 LAST LOCATION C2U20
J 0
(-3225 775);
DISPLAY 0.617021 (-3225 775);
PAINT AQUA (-3225 775);
FORCEPROP 1 LAST PART_NUMBER A36096-030
J 0
(-3225 525);
DISPLAY 0.617021 (-3225 525);
PAINT BLUE (-3225 525);
FORCEPROP 2 LAST CDS_LIB dev_discrete
J 0
(-3275 675);
PAINT ORANGE (-3275 675);
DISPLAY INVISIBLE (-3275 675);
FORCEPROP 2 LAST CDS_SEC 1
J 0
(-3225 825);
PAINT ORANGE (-3225 825);
DISPLAY INVISIBLE (-3225 825);
FORCEPROP 1 LAST PATH I1
J 0
(-3225 825);
DISPLAY 0.978723 (-3225 825);
PAINT WHITE (-3225 825);
DISPLAY INVISIBLE (-3225 825);
FORCEPROP 2 LAST CDS_LOCATION C2U20
J 0
(-3225 775);
DISPLAY 0.617021 (-3225 775);
PAINT AQUA (-3225 775);
DISPLAY INVISIBLE (-3225 775);
FORCEPROP 2 LAST SEC 1
J 0
(-3225 875);
DISPLAY 0.680851 (-3225 875);
PAINT MONO (-3225 875);
DISPLAY INVISIBLE (-3225 875);
FORCEPROP 2 LAST SEC_TYPE 0402V
J 0
(-3225 875);
DISPLAY 1.021277 (-3225 875);
PAINT ORANGE (-3225 875);
DISPLAY INVISIBLE (-3225 875);
FORCEPROP 0 LAST ROOM IO_SLOT
J 0
(-3225 875);
DISPLAY 1.021277 (-3225 875);
PAINT ORANGE (-3225 875);
DISPLAY INVISIBLE (-3225 875);
FORCEADD P12V..1
(1375 4675);
FORCEPROP 3 LASTPIN (1375 4625) SIG_NAME P12V\g
J 0
(1385 4635);
DISPLAY 0.659574 (1385 4635);
PAINT MONO (1385 4635);
DISPLAY INVISIBLE (1385 4635);
FORCEPROP 1 LAST HDL_POWER P12V
J 0
(1175 4525);
DISPLAY 0.638298 (1175 4525);
PAINT GREEN (1175 4525);
DISPLAY INVISIBLE (1175 4525);
FORCEPROP 1 LAST SIZE 1B
J 0
(1420 4697);
DISPLAY 0.255319 (1420 4697);
PAINT GREEN (1420 4697);
DISPLAY INVISIBLE (1420 4697);
FORCEPROP 2 LAST CDS_LIB mstr_symbols
J 0
(1375 4675);
PAINT ORANGE (1375 4675);
DISPLAY INVISIBLE (1375 4675);
FORCEPROP 1 LAST BODY_TYPE PLUMBING
J 0
(1330 4632);
DISPLAY 0.255319 (1330 4632);
PAINT GREEN (1330 4632);
DISPLAY INVISIBLE (1330 4632);
FORCEPROP 1 LAST PATH I165
J 0
(1420 4677);
DISPLAY 0.340426 (1420 4677);
PAINT GREEN (1420 4677);
DISPLAY INVISIBLE (1420 4677);
FORCEPROP 1 LAST VOLTAGE +12.
J 0
(1375 4675);
PAINT SKYBLUE (1375 4675);
DISPLAY INVISIBLE (1375 4675);
FORCEADD P12V..1
(-350 4725);
FORCEPROP 3 LASTPIN (-350 4675) SIG_NAME P12V\g
J 0
(-340 4685);
DISPLAY 0.659574 (-340 4685);
PAINT MONO (-340 4685);
DISPLAY INVISIBLE (-340 4685);
FORCEPROP 1 LAST HDL_POWER P12V
J 0
(-550 4575);
DISPLAY 0.638298 (-550 4575);
PAINT GREEN (-550 4575);
DISPLAY INVISIBLE (-550 4575);
FORCEPROP 1 LAST PATH I167
J 0
(-305 4727);
DISPLAY 0.340426 (-305 4727);
PAINT GREEN (-305 4727);
DISPLAY INVISIBLE (-305 4727);
FORCEPROP 1 LAST BODY_TYPE PLUMBING
J 0
(-395 4682);
DISPLAY 0.255319 (-395 4682);
PAINT GREEN (-395 4682);
DISPLAY INVISIBLE (-395 4682);
FORCEPROP 2 LAST CDS_LIB mstr_symbols
J 0
(-350 4725);
PAINT ORANGE (-350 4725);
DISPLAY INVISIBLE (-350 4725);
FORCEPROP 1 LAST SIZE 1B
J 0
(-305 4747);
DISPLAY 0.255319 (-305 4747);
PAINT GREEN (-305 4747);
DISPLAY INVISIBLE (-305 4747);
FORCEPROP 1 LAST VOLTAGE +12.
J 0
(-350 4725);
PAINT SKYBLUE (-350 4725);
DISPLAY INVISIBLE (-350 4725);
FORCEADD GND..1
(-100 1600);
FORCEPROP 3 LASTPIN (-100 1650) SIG_NAME GND\g
J 0
(-90 1660);
DISPLAY 0.659574 (-90 1660);
PAINT MONO (-90 1660);
DISPLAY INVISIBLE (-90 1660);
FORCEPROP 1 LAST HDL_POWER GND
J 0
(-100 1750);
DISPLAY 0.638298 (-100 1750);
PAINT GREEN (-100 1750);
DISPLAY INVISIBLE (-100 1750);
FORCEPROP 1 LAST PATH I168
J 0
(-25 1600);
DISPLAY 0.872340 (-25 1600);
PAINT AQUA (-25 1600);
DISPLAY INVISIBLE (-25 1600);
FORCEPROP 1 LAST BODY_TYPE PLUMBING
J 0
(-145 1557);
DISPLAY 0.340426 (-145 1557);
PAINT GREEN (-145 1557);
DISPLAY INVISIBLE (-145 1557);
FORCEPROP 1 LAST SIZE 1B
J 0
(-25 1550);
DISPLAY 0.638298 (-25 1550);
PAINT GREEN (-25 1550);
DISPLAY INVISIBLE (-25 1550);
FORCEPROP 2 LAST CDS_LIB mstr_symbols
J 0
(-100 1600);
PAINT ORANGE (-100 1600);
DISPLAY INVISIBLE (-100 1600);
FORCEPROP 1 LAST VOLTAGE 0
J 0
(-100 1600);
PAINT SKYBLUE (-100 1600);
DISPLAY INVISIBLE (-100 1600);
FORCEADD P3V3..1
(-525 4100);
FORCEPROP 3 LASTPIN (-525 4050) SIG_NAME P3V3\g
J 0
(-515 4060);
DISPLAY 0.659574 (-515 4060);
PAINT MONO (-515 4060);
DISPLAY INVISIBLE (-515 4060);
FORCEPROP 1 LAST SIZE 1B
J 0
(-480 4122);
DISPLAY 0.340426 (-480 4122);
PAINT GREEN (-480 4122);
DISPLAY INVISIBLE (-480 4122);
FORCEPROP 1 LAST PATH I172
J 0
(-480 4102);
DISPLAY 0.340426 (-480 4102);
PAINT GREEN (-480 4102);
DISPLAY INVISIBLE (-480 4102);
FORCEPROP 1 LAST VOLTAGE 3.3V
J 0
(-570 4057);
DISPLAY 0.340426 (-570 4057);
PAINT SKYBLUE (-570 4057);
DISPLAY INVISIBLE (-570 4057);
FORCEPROP 2 LAST CDS_LIB mstr_symbols
J 0
(-525 4100);
PAINT ORANGE (-525 4100);
DISPLAY INVISIBLE (-525 4100);
FORCEPROP 1 LAST BODY_TYPE PLUMBING
J 0
(-570 4057);
DISPLAY 0.340426 (-570 4057);
PAINT GREEN (-570 4057);
DISPLAY INVISIBLE (-570 4057);
FORCEPROP 1 LAST HDL_POWER P3V3
J 0
(-850 3975);
DISPLAY 0.872340 (-850 3975);
PAINT ORANGE (-850 3975);
DISPLAY INVISIBLE (-850 3975);
FORCEADD RES..1
(-1100 3625);
FORCEPROP 1 LAST WATTAGE 1/16W
J 2
(-1200 3575);
DISPLAY 0.617021 (-1200 3575);
PAINT SKYBLUE (-1200 3575);
FORCEPROP 1 LASTPIN (-1200 3625) $PN 1
J 0
(-1188 3637);
DISPLAY 0.617021 (-1188 3637);
PAINT ORANGE (-1188 3637);
FORCEPROP 1 LAST TOLERANCE 5%
J 0
(-1425 3575);
DISPLAY 0.617021 (-1425 3575);
PAINT SKYBLUE (-1425 3575);
FORCEPROP 1 LAST LOCATION R2U37
J 0
(-1700 3575);
DISPLAY 0.617021 (-1700 3575);
PAINT AQUA (-1700 3575);
FORCEPROP 1 LASTPIN (-1000 3625) $PN 2
J 0
(-1038 3637);
DISPLAY 0.617021 (-1038 3637);
PAINT ORANGE (-1038 3637);
FORCEPROP 1 LAST PART_NUMBER G21497-005
J 0
(-1025 3575);
DISPLAY 0.617021 (-1025 3575);
PAINT BLUE (-1025 3575);
FORCEPROP 1 LAST MATERIAL CHIP
J 0
(-1150 3575);
DISPLAY 0.617021 (-1150 3575);
PAINT SKYBLUE (-1150 3575);
FORCEPROP 1 LAST PACK_TYPE 0402
J 0
(-700 3575);
DISPLAY 0.617021 (-700 3575);
PAINT SKYBLUE (-700 3575);
FORCEPROP 1 LAST VALUE 0.0
J 2
(-1475 3575);
DISPLAY 0.617021 (-1475 3575);
PAINT SKYBLUE (-1475 3575);
FORCEPROP 2 LAST SEC_TYPE 0402
J 0
(-1150 3825);
DISPLAY 1.021277 (-1150 3825);
PAINT ORANGE (-1150 3825);
DISPLAY INVISIBLE (-1150 3825);
FORCEPROP 2 LAST SEC 1
J 0
(-1150 3825);
DISPLAY 0.680851 (-1150 3825);
PAINT MONO (-1150 3825);
DISPLAY INVISIBLE (-1150 3825);
FORCEPROP 0 LAST ROOM IO_SLOT
J 0
(-1150 3825);
DISPLAY 1.021277 (-1150 3825);
PAINT ORANGE (-1150 3825);
DISPLAY INVISIBLE (-1150 3825);
FORCEPROP 2 LAST CDS_LIB mstr_discrete
J 0
(-1100 3625);
PAINT MONO (-1100 3625);
DISPLAY INVISIBLE (-1100 3625);
FORCEPROP 2 LAST CDS_LOCATION R2U37
J 0
(-1150 3675);
DISPLAY 0.617021 (-1150 3675);
PAINT AQUA (-1150 3675);
DISPLAY INVISIBLE (-1150 3675);
FORCEPROP 1 LAST PATH I173
J 0
(-1150 3775);
DISPLAY 0.978723 (-1150 3775);
PAINT WHITE (-1150 3775);
DISPLAY INVISIBLE (-1150 3775);
FORCEADD OFFPAGE..1
(-2000 3625);
FORCEPROP 2 LAST $XR0 190 
J 0
(-2282 3625);
DISPLAY 0.638298 (-2282 3625);
PAINT MONO (-2282 3625);
FORCEPROP 1 LAST COMMENT_BODY TRUE
J 0
(-1875 3525);
DISPLAY 0.872340 (-1875 3525);
PAINT GREEN (-1875 3525);
DISPLAY INVISIBLE (-1875 3525);
FORCEPROP 1 LAST OFFPAGE TRUE
J 0
(-1675 3500);
DISPLAY 0.872340 (-1675 3500);
PAINT GREEN (-1675 3500);
DISPLAY INVISIBLE (-1675 3500);
FORCEPROP 2 LAST PATH I174
J 0
(-1950 3700);
DISPLAY 1.021277 (-1950 3700);
PAINT ORANGE (-1950 3700);
DISPLAY INVISIBLE (-1950 3700);
FORCEPROP 2 LAST CDS_LIB mstr_standard
J 0
(-2000 3625);
PAINT ORANGE (-2000 3625);
DISPLAY INVISIBLE (-2000 3625);
FORCEADD OFFPAGE..1
(-2000 3375);
FORCEPROP 2 LAST $XR0 114 
J 0
(-2252 3375);
DISPLAY 0.638298 (-2252 3375);
PAINT MONO (-2252 3375);
FORCEPROP 1 LAST COMMENT_BODY TRUE
J 0
(-1875 3275);
DISPLAY 0.872340 (-1875 3275);
PAINT GREEN (-1875 3275);
DISPLAY INVISIBLE (-1875 3275);
FORCEPROP 2 LAST CDS_LIB mstr_standard
J 0
(-2000 3375);
PAINT ORANGE (-2000 3375);
DISPLAY INVISIBLE (-2000 3375);
FORCEPROP 2 LAST PATH I175
J 0
(-1950 3450);
DISPLAY 1.021277 (-1950 3450);
PAINT ORANGE (-1950 3450);
DISPLAY INVISIBLE (-1950 3450);
FORCEPROP 1 LAST OFFPAGE TRUE
J 0
(-1675 3250);
DISPLAY 0.872340 (-1675 3250);
PAINT GREEN (-1675 3250);
DISPLAY INVISIBLE (-1675 3250);
FORCEADD OFFPAGE..1
(-2000 3325);
FORCEPROP 2 LAST $XR0 114 
J 0
(-2252 3325);
DISPLAY 0.638298 (-2252 3325);
PAINT MONO (-2252 3325);
FORCEPROP 1 LAST COMMENT_BODY TRUE
J 0
(-1875 3225);
DISPLAY 0.872340 (-1875 3225);
PAINT GREEN (-1875 3225);
DISPLAY INVISIBLE (-1875 3225);
FORCEPROP 2 LAST CDS_LIB mstr_standard
J 0
(-2000 3325);
PAINT ORANGE (-2000 3325);
DISPLAY INVISIBLE (-2000 3325);
FORCEPROP 2 LAST PATH I176
J 0
(-1950 3400);
DISPLAY 1.021277 (-1950 3400);
PAINT ORANGE (-1950 3400);
DISPLAY INVISIBLE (-1950 3400);
FORCEPROP 1 LAST OFFPAGE TRUE
J 0
(-1675 3200);
DISPLAY 0.872340 (-1675 3200);
PAINT GREEN (-1675 3200);
DISPLAY INVISIBLE (-1675 3200);
FORCEADD CAP_A..1
(-2875 650);
FORCEPROP 1 LAST PACK_TYPE 0402V
J 0
(-2825 450);
DISPLAY 0.617021 (-2825 450);
PAINT SKYBLUE (-2825 450);
FORCEPROP 1 LASTPIN (-2875 550) $PN 2
J 0
(-2865 530);
DISPLAY 0.617021 (-2865 530);
PAINT ORANGE (-2865 530);
FORCEPROP 1 LASTPIN (-2875 750) $PN 1
J 0
(-2865 730);
DISPLAY 0.617021 (-2865 730);
PAINT ORANGE (-2865 730);
FORCEPROP 1 LAST MATERIAL X7R
J 0
(-2825 550);
DISPLAY 0.617021 (-2825 550);
PAINT SKYBLUE (-2825 550);
FORCEPROP 1 LAST VOLTAGE 16V
J 0
(-2825 650);
DISPLAY 0.617021 (-2825 650);
PAINT SKYBLUE (-2825 650);
FORCEPROP 1 LAST TOLERANCE 10%
J 0
(-2825 600);
DISPLAY 0.617021 (-2825 600);
PAINT SKYBLUE (-2825 600);
FORCEPROP 1 LAST VALUE 0.1UF
J 0
(-2825 700);
DISPLAY 0.617021 (-2825 700);
PAINT SKYBLUE (-2825 700);
FORCEPROP 1 LAST LOCATION C2U24
J 0
(-2825 750);
DISPLAY 0.617021 (-2825 750);
PAINT AQUA (-2825 750);
FORCEPROP 1 LAST PART_NUMBER A36096-030
J 0
(-2825 500);
DISPLAY 0.617021 (-2825 500);
PAINT BLUE (-2825 500);
FORCEPROP 2 LAST CDS_LIB dev_discrete
J 0
(-2875 650);
PAINT ORANGE (-2875 650);
DISPLAY INVISIBLE (-2875 650);
FORCEPROP 2 LAST CDS_LOCATION C2U24
J 0
(-2825 750);
DISPLAY 0.617021 (-2825 750);
PAINT AQUA (-2825 750);
DISPLAY INVISIBLE (-2825 750);
FORCEPROP 2 LAST SEC 1
J 0
(-2825 850);
DISPLAY 0.680851 (-2825 850);
PAINT MONO (-2825 850);
DISPLAY INVISIBLE (-2825 850);
FORCEPROP 2 LAST SEC_TYPE 0402V
J 0
(-2825 850);
DISPLAY 1.021277 (-2825 850);
PAINT ORANGE (-2825 850);
DISPLAY INVISIBLE (-2825 850);
FORCEPROP 2 LAST CDS_SEC 1
J 0
(-2825 800);
PAINT ORANGE (-2825 800);
DISPLAY INVISIBLE (-2825 800);
FORCEPROP 1 LAST PATH I2
J 0
(-2825 800);
DISPLAY 0.978723 (-2825 800);
PAINT WHITE (-2825 800);
DISPLAY INVISIBLE (-2825 800);
FORCEPROP 0 LAST ROOM IO_SLOT
J 0
(-2825 850);
DISPLAY 1.021277 (-2825 850);
PAINT ORANGE (-2825 850);
DISPLAY INVISIBLE (-2825 850);
FORCEADD GND..1
(1050 1600);
FORCEPROP 3 LASTPIN (1050 1650) SIG_NAME GND\g
J 0
(1060 1660);
DISPLAY 0.659574 (1060 1660);
PAINT MONO (1060 1660);
DISPLAY INVISIBLE (1060 1660);
FORCEPROP 1 LAST VOLTAGE 0
J 0
(1050 1600);
PAINT SKYBLUE (1050 1600);
DISPLAY INVISIBLE (1050 1600);
FORCEPROP 1 LAST SIZE 1B
J 0
(1125 1550);
DISPLAY 0.638298 (1125 1550);
PAINT GREEN (1125 1550);
DISPLAY INVISIBLE (1125 1550);
FORCEPROP 2 LAST CDS_LIB mstr_symbols
J 0
(1050 1600);
PAINT ORANGE (1050 1600);
DISPLAY INVISIBLE (1050 1600);
FORCEPROP 1 LAST PATH I236
J 0
(1125 1600);
DISPLAY 0.872340 (1125 1600);
PAINT AQUA (1125 1600);
DISPLAY INVISIBLE (1125 1600);
FORCEPROP 1 LAST HDL_POWER GND
J 0
(1050 1750);
DISPLAY 0.638298 (1050 1750);
PAINT GREEN (1050 1750);
DISPLAY INVISIBLE (1050 1750);
FORCEPROP 1 LAST BODY_TYPE PLUMBING
J 0
(1005 1557);
DISPLAY 0.340426 (1005 1557);
PAINT GREEN (1005 1557);
DISPLAY INVISIBLE (1005 1557);
FORCEADD P3V3..1
(1600 4675);
FORCEPROP 3 LASTPIN (1600 4625) SIG_NAME P3V3\g
J 0
(1610 4635);
DISPLAY 0.659574 (1610 4635);
PAINT MONO (1610 4635);
DISPLAY INVISIBLE (1610 4635);
FORCEPROP 1 LAST HDL_POWER P3V3
J 0
(1275 4550);
DISPLAY 0.872340 (1275 4550);
PAINT ORANGE (1275 4550);
DISPLAY INVISIBLE (1275 4550);
FORCEPROP 1 LAST PATH I238
J 0
(1645 4677);
DISPLAY 0.340426 (1645 4677);
PAINT GREEN (1645 4677);
DISPLAY INVISIBLE (1645 4677);
FORCEPROP 1 LAST BODY_TYPE PLUMBING
J 0
(1555 4632);
DISPLAY 0.340426 (1555 4632);
PAINT GREEN (1555 4632);
DISPLAY INVISIBLE (1555 4632);
FORCEPROP 2 LAST CDS_LIB mstr_symbols
J 0
(1600 4675);
PAINT ORANGE (1600 4675);
DISPLAY INVISIBLE (1600 4675);
FORCEPROP 1 LAST SIZE 1B
J 0
(1645 4697);
DISPLAY 0.340426 (1645 4697);
PAINT GREEN (1645 4697);
DISPLAY INVISIBLE (1645 4697);
FORCEPROP 1 LAST VOLTAGE 3.3V
J 0
(1555 4632);
DISPLAY 0.340426 (1555 4632);
PAINT SKYBLUE (1555 4632);
DISPLAY INVISIBLE (1555 4632);
FORCEADD OFFPAGE..2
(2850 3975);
FORCEPROP 2 LAST $XR2 145 
J 0
(3279 3975);
DISPLAY 0.638298 (3279 3975);
PAINT MONO (3279 3975);
FORCEPROP 2 LAST $XR1 119 
J 0
(3159 3975);
DISPLAY 0.638298 (3159 3975);
PAINT MONO (3159 3975);
FORCEPROP 2 LAST $XR0 157 
J 0
(3039 3975);
DISPLAY 0.638298 (3039 3975);
PAINT MONO (3039 3975);
FORCEPROP 1 LAST COMMENT_BODY TRUE
J 0
(2805 3880);
DISPLAY 0.872340 (2805 3880);
PAINT GREEN (2805 3880);
DISPLAY INVISIBLE (2805 3880);
FORCEPROP 2 LAST CDS_LIB mstr_standard
J 0
(2850 3975);
PAINT ORANGE (2850 3975);
DISPLAY INVISIBLE (2850 3975);
FORCEPROP 2 LAST PATH I243
J 0
(3025 4050);
DISPLAY 1.021277 (3025 4050);
PAINT ORANGE (3025 4050);
DISPLAY INVISIBLE (3025 4050);
FORCEPROP 1 LAST OFFPAGE TRUE
J 0
(3175 3850);
DISPLAY 0.872340 (3175 3850);
PAINT GREEN (3175 3850);
DISPLAY INVISIBLE (3175 3850);
FORCEADD GND..1
(-2875 300);
FORCEPROP 3 LASTPIN (-2875 350) SIG_NAME GND\g
J 0
(-2865 360);
DISPLAY 0.659574 (-2865 360);
PAINT MONO (-2865 360);
DISPLAY INVISIBLE (-2865 360);
FORCEPROP 1 LAST BODY_TYPE PLUMBING
J 0
(-2920 257);
DISPLAY 0.340426 (-2920 257);
PAINT GREEN (-2920 257);
DISPLAY INVISIBLE (-2920 257);
FORCEPROP 2 LAST CDS_LIB mstr_symbols
J 0
(-2875 300);
PAINT ORANGE (-2875 300);
DISPLAY INVISIBLE (-2875 300);
FORCEPROP 1 LAST VOLTAGE 0
J 0
(-2875 300);
PAINT SKYBLUE (-2875 300);
DISPLAY INVISIBLE (-2875 300);
FORCEPROP 1 LAST HDL_POWER GND
J 0
(-2875 450);
DISPLAY 0.872340 (-2875 450);
PAINT GREEN (-2875 450);
DISPLAY INVISIBLE (-2875 450);
FORCEPROP 1 LAST SIZE 1B
J 0
(-2800 250);
DISPLAY 0.872340 (-2800 250);
PAINT AQUA (-2800 250);
DISPLAY INVISIBLE (-2800 250);
FORCEPROP 1 LAST PATH I250
J 0
(-2800 300);
DISPLAY 0.872340 (-2800 300);
PAINT AQUA (-2800 300);
DISPLAY INVISIBLE (-2800 300);
FORCEADD P3V3..1
(-3275 1650);
FORCEPROP 3 LASTPIN (-3275 1600) SIG_NAME P3V3\g
J 0
(-3265 1610);
DISPLAY 0.659574 (-3265 1610);
PAINT MONO (-3265 1610);
DISPLAY INVISIBLE (-3265 1610);
FORCEPROP 1 LAST HDL_POWER P3V3
J 0
(-3600 1525);
DISPLAY 0.872340 (-3600 1525);
PAINT ORANGE (-3600 1525);
DISPLAY INVISIBLE (-3600 1525);
FORCEPROP 1 LAST VOLTAGE 3.3V
J 0
(-3320 1607);
DISPLAY 0.340426 (-3320 1607);
PAINT SKYBLUE (-3320 1607);
DISPLAY INVISIBLE (-3320 1607);
FORCEPROP 1 LAST BODY_TYPE PLUMBING
J 0
(-3320 1607);
DISPLAY 0.340426 (-3320 1607);
PAINT GREEN (-3320 1607);
DISPLAY INVISIBLE (-3320 1607);
FORCEPROP 1 LAST PATH I251
J 0
(-3230 1652);
DISPLAY 0.340426 (-3230 1652);
PAINT GREEN (-3230 1652);
DISPLAY INVISIBLE (-3230 1652);
FORCEPROP 2 LAST CDS_LIB mstr_symbols
J 0
(-3275 1650);
PAINT ORANGE (-3275 1650);
DISPLAY INVISIBLE (-3275 1650);
FORCEPROP 1 LAST SIZE 1B
J 0
(-3230 1672);
DISPLAY 0.340426 (-3230 1672);
PAINT GREEN (-3230 1672);
DISPLAY INVISIBLE (-3230 1672);
FORCEADD GND..1
(-2875 975);
FORCEPROP 3 LASTPIN (-2875 1025) SIG_NAME GND\g
J 0
(-2865 1035);
DISPLAY 0.659574 (-2865 1035);
PAINT MONO (-2865 1035);
DISPLAY INVISIBLE (-2865 1035);
FORCEPROP 1 LAST BODY_TYPE PLUMBING
J 0
(-2920 932);
DISPLAY 0.340426 (-2920 932);
PAINT GREEN (-2920 932);
DISPLAY INVISIBLE (-2920 932);
FORCEPROP 2 LAST CDS_LIB mstr_symbols
J 0
(-2875 975);
PAINT ORANGE (-2875 975);
DISPLAY INVISIBLE (-2875 975);
FORCEPROP 1 LAST VOLTAGE 0
J 0
(-2875 975);
PAINT SKYBLUE (-2875 975);
DISPLAY INVISIBLE (-2875 975);
FORCEPROP 1 LAST SIZE 1B
J 0
(-2800 925);
DISPLAY 0.872340 (-2800 925);
PAINT AQUA (-2800 925);
DISPLAY INVISIBLE (-2800 925);
FORCEPROP 1 LAST PATH I252
J 0
(-2800 975);
DISPLAY 0.872340 (-2800 975);
PAINT AQUA (-2800 975);
DISPLAY INVISIBLE (-2800 975);
FORCEPROP 1 LAST HDL_POWER GND
J 0
(-2875 1125);
DISPLAY 0.872340 (-2875 1125);
PAINT GREEN (-2875 1125);
DISPLAY INVISIBLE (-2875 1125);
FORCEADD SCONN200_H68296001..1
(500 3075);
FORCEPROP 2 LASTPIN (200 3925) $PN 17
J 2
(190 3935);
DISPLAY 0.617021 (190 3935);
PAINT ORANGE (190 3935);
FORCEPROP 2 LASTPIN (200 3325) $PN 41
J 2
(190 3335);
DISPLAY 0.617021 (190 3335);
PAINT ORANGE (190 3335);
FORCEPROP 2 LASTPIN (200 3475) $PN 35
J 2
(190 3485);
DISPLAY 0.617021 (190 3485);
PAINT ORANGE (190 3485);
FORCEPROP 2 LASTPIN (200 2925) $PN 57
J 2
(190 2935);
DISPLAY 0.617021 (190 2935);
PAINT ORANGE (190 2935);
FORCEPROP 2 LASTPIN (800 2875) $PN 60
J 0
(810 2885);
DISPLAY 0.617021 (810 2885);
PAINT ORANGE (810 2885);
FORCEPROP 2 LASTPIN (200 3825) $PN 21
J 2
(190 3835);
DISPLAY 0.617021 (190 3835);
PAINT ORANGE (190 3835);
FORCEPROP 2 LASTPIN (800 1975) $PN 96
J 0
(810 1985);
DISPLAY 0.617021 (810 1985);
PAINT ORANGE (810 1985);
FORCEPROP 2 LASTPIN (200 2125) $PN 89
J 2
(190 2135);
DISPLAY 0.617021 (190 2135);
PAINT ORANGE (190 2135);
FORCEPROP 2 LASTPIN (200 2475) $PN 75
J 2
(190 2485);
DISPLAY 0.617021 (190 2485);
PAINT ORANGE (190 2485);
FORCEPROP 2 LASTPIN (800 2425) $PN 78
J 0
(810 2435);
DISPLAY 0.617021 (810 2435);
PAINT ORANGE (810 2435);
FORCEPROP 2 LASTPIN (800 2375) $PN 80
J 0
(810 2385);
DISPLAY 0.617021 (810 2385);
PAINT ORANGE (810 2385);
FORCEPROP 2 LASTPIN (800 3025) $PN 54
J 0
(810 3035);
DISPLAY 0.617021 (810 3035);
PAINT ORANGE (810 3035);
FORCEPROP 2 LASTPIN (200 1975) $PN 95
J 2
(190 1985);
DISPLAY 0.617021 (190 1985);
PAINT ORANGE (190 1985);
FORCEPROP 1 LAST PART_NUMBER H68296-001
J 0
(250 1675);
DISPLAY 0.617021 (250 1675);
PAINT BLUE (250 1675);
FORCEPROP 2 LASTPIN (800 2525) $PN 74
J 0
(810 2535);
DISPLAY 0.617021 (810 2535);
PAINT ORANGE (810 2535);
FORCEPROP 2 LASTPIN (800 3775) $PN 24
J 0
(810 3785);
DISPLAY 0.617021 (810 3785);
PAINT ORANGE (810 3785);
FORCEPROP 1 LAST LOCATION J8G1
J 0
(225 4575);
DISPLAY 0.617021 (225 4575);
PAINT AQUA (225 4575);
FORCEPROP 1 LAST MATERIAL CONN
J 0
(250 4525);
DISPLAY 0.617021 (250 4525);
PAINT SKYBLUE (250 4525);
FORCEPROP 2 LASTPIN (800 3425) $PN 38
J 0
(810 3435);
DISPLAY 0.617021 (810 3435);
PAINT ORANGE (810 3435);
FORCEPROP 2 LASTPIN (800 3375) $PN 40
J 0
(810 3385);
DISPLAY 0.617021 (810 3385);
PAINT ORANGE (810 3385);
FORCEPROP 2 LASTPIN (800 2225) $PN 86
J 0
(810 2235);
DISPLAY 0.617021 (810 2235);
PAINT ORANGE (810 2235);
FORCEPROP 2 LASTPIN (200 2875) $PN 59
J 2
(190 2885);
DISPLAY 0.617021 (190 2885);
PAINT ORANGE (190 2885);
FORCEPROP 2 LASTPIN (200 2025) $PN 93
J 2
(190 2035);
DISPLAY 0.617021 (190 2035);
PAINT ORANGE (190 2035);
FORCEPROP 2 LASTPIN (800 2475) $PN 76
J 0
(810 2485);
DISPLAY 0.617021 (810 2485);
PAINT ORANGE (810 2485);
FORCEPROP 2 LASTPIN (200 2325) $PN 81
J 2
(190 2335);
DISPLAY 0.617021 (190 2335);
PAINT ORANGE (190 2335);
FORCEPROP 2 LASTPIN (200 3125) $PN 49
J 2
(190 3135);
DISPLAY 0.617021 (190 3135);
PAINT ORANGE (190 3135);
FORCEPROP 2 LASTPIN (200 1825) $PN MH1
J 2
(190 1835);
DISPLAY 0.617021 (190 1835);
PAINT ORANGE (190 1835);
FORCEPROP 2 LASTPIN (200 1875) $PN 99
J 2
(190 1885);
DISPLAY 0.617021 (190 1885);
PAINT ORANGE (190 1885);
FORCEPROP 2 LASTPIN (200 1925) $PN 97
J 2
(190 1935);
DISPLAY 0.617021 (190 1935);
PAINT ORANGE (190 1935);
FORCEPROP 2 LASTPIN (800 1925) $PN 98
J 0
(810 1935);
DISPLAY 0.617021 (810 1935);
PAINT ORANGE (810 1935);
FORCEPROP 2 LASTPIN (800 1825) $PN MH2
J 0
(810 1835);
DISPLAY 0.617021 (810 1835);
PAINT ORANGE (810 1835);
FORCEPROP 2 LASTPIN (800 1875) $PN 100
J 0
(810 1885);
DISPLAY 0.617021 (810 1885);
PAINT ORANGE (810 1885);
FORCEPROP 2 LASTPIN (800 2025) $PN 94
J 0
(810 2035);
DISPLAY 0.617021 (810 2035);
PAINT ORANGE (810 2035);
FORCEPROP 2 LASTPIN (200 2075) $PN 91
J 2
(190 2085);
DISPLAY 0.617021 (190 2085);
PAINT ORANGE (190 2085);
FORCEPROP 2 LASTPIN (200 2175) $PN 87
J 2
(190 2185);
DISPLAY 0.617021 (190 2185);
PAINT ORANGE (190 2185);
FORCEPROP 2 LASTPIN (200 2275) $PN 83
J 2
(190 2285);
DISPLAY 0.617021 (190 2285);
PAINT ORANGE (190 2285);
FORCEPROP 2 LASTPIN (200 2375) $PN 79
J 2
(190 2385);
DISPLAY 0.617021 (190 2385);
PAINT ORANGE (190 2385);
FORCEPROP 2 LASTPIN (200 2425) $PN 77
J 2
(190 2435);
DISPLAY 0.617021 (190 2435);
PAINT ORANGE (190 2435);
FORCEPROP 2 LASTPIN (200 2525) $PN 73
J 2
(190 2535);
DISPLAY 0.617021 (190 2535);
PAINT ORANGE (190 2535);
FORCEPROP 2 LASTPIN (200 2625) $PN 69
J 2
(190 2635);
DISPLAY 0.617021 (190 2635);
PAINT ORANGE (190 2635);
FORCEPROP 2 LASTPIN (200 2575) $PN 71
J 2
(190 2585);
DISPLAY 0.617021 (190 2585);
PAINT ORANGE (190 2585);
FORCEPROP 2 LASTPIN (200 2675) $PN 67
J 2
(190 2685);
DISPLAY 0.617021 (190 2685);
PAINT ORANGE (190 2685);
FORCEPROP 2 LASTPIN (200 2775) $PN 63
J 2
(190 2785);
DISPLAY 0.617021 (190 2785);
PAINT ORANGE (190 2785);
FORCEPROP 2 LASTPIN (200 2725) $PN 65
J 2
(190 2735);
DISPLAY 0.617021 (190 2735);
PAINT ORANGE (190 2735);
FORCEPROP 2 LASTPIN (200 2825) $PN 61
J 2
(190 2835);
DISPLAY 0.617021 (190 2835);
PAINT ORANGE (190 2835);
FORCEPROP 2 LASTPIN (200 3025) $PN 53
J 2
(190 3035);
DISPLAY 0.617021 (190 3035);
PAINT ORANGE (190 3035);
FORCEPROP 2 LASTPIN (800 2075) $PN 92
J 0
(810 2085);
DISPLAY 0.617021 (810 2085);
PAINT ORANGE (810 2085);
FORCEPROP 2 LASTPIN (800 2125) $PN 90
J 0
(810 2135);
DISPLAY 0.617021 (810 2135);
PAINT ORANGE (810 2135);
FORCEPROP 2 LASTPIN (800 2275) $PN 84
J 0
(810 2285);
DISPLAY 0.617021 (810 2285);
PAINT ORANGE (810 2285);
FORCEPROP 2 LASTPIN (800 2325) $PN 82
J 0
(810 2335);
DISPLAY 0.617021 (810 2335);
PAINT ORANGE (810 2335);
FORCEPROP 2 LASTPIN (800 2725) $PN 66
J 0
(810 2735);
DISPLAY 0.617021 (810 2735);
PAINT ORANGE (810 2735);
FORCEPROP 2 LASTPIN (800 2675) $PN 68
J 0
(810 2685);
DISPLAY 0.617021 (810 2685);
PAINT ORANGE (810 2685);
FORCEPROP 2 LASTPIN (800 2575) $PN 72
J 0
(810 2585);
DISPLAY 0.617021 (810 2585);
PAINT ORANGE (810 2585);
FORCEPROP 2 LASTPIN (800 2625) $PN 70
J 0
(810 2635);
DISPLAY 0.617021 (810 2635);
PAINT ORANGE (810 2635);
FORCEPROP 2 LASTPIN (800 2825) $PN 62
J 0
(810 2835);
DISPLAY 0.617021 (810 2835);
PAINT ORANGE (810 2835);
FORCEPROP 2 LASTPIN (800 2925) $PN 58
J 0
(810 2935);
DISPLAY 0.617021 (810 2935);
PAINT ORANGE (810 2935);
FORCEPROP 2 LASTPIN (800 2975) $PN 56
J 0
(810 2985);
DISPLAY 0.617021 (810 2985);
PAINT ORANGE (810 2985);
FORCEPROP 2 LASTPIN (200 3075) $PN 51
J 2
(190 3085);
DISPLAY 0.617021 (190 3085);
PAINT ORANGE (190 3085);
FORCEPROP 2 LASTPIN (200 3225) $PN 45
J 2
(190 3235);
DISPLAY 0.617021 (190 3235);
PAINT ORANGE (190 3235);
FORCEPROP 2 LASTPIN (200 3625) $PN 29
J 2
(190 3635);
DISPLAY 0.617021 (190 3635);
PAINT ORANGE (190 3635);
FORCEPROP 2 LASTPIN (200 3575) $PN 31
J 2
(190 3585);
DISPLAY 0.617021 (190 3585);
PAINT ORANGE (190 3585);
FORCEPROP 2 LASTPIN (800 3275) $PN 44
J 0
(810 3285);
DISPLAY 0.617021 (810 3285);
PAINT ORANGE (810 3285);
FORCEPROP 2 LASTPIN (800 3325) $PN 42
J 0
(810 3335);
DISPLAY 0.617021 (810 3335);
PAINT ORANGE (810 3335);
FORCEPROP 2 LASTPIN (800 3475) $PN 36
J 0
(810 3485);
DISPLAY 0.617021 (810 3485);
PAINT ORANGE (810 3485);
FORCEPROP 2 LASTPIN (800 3525) $PN 34
J 0
(810 3535);
DISPLAY 0.617021 (810 3535);
PAINT ORANGE (810 3535);
FORCEPROP 2 LASTPIN (800 3675) $PN 28
J 0
(810 3685);
DISPLAY 0.617021 (810 3685);
PAINT ORANGE (810 3685);
FORCEPROP 2 LASTPIN (800 3825) $PN 22
J 0
(810 3835);
DISPLAY 0.617021 (810 3835);
PAINT ORANGE (810 3835);
FORCEPROP 2 LASTPIN (800 3875) $PN 20
J 0
(810 3885);
DISPLAY 0.617021 (810 3885);
PAINT ORANGE (810 3885);
FORCEPROP 2 LASTPIN (800 3925) $PN 18
J 0
(810 3935);
DISPLAY 0.617021 (810 3935);
PAINT ORANGE (810 3935);
FORCEPROP 2 LASTPIN (800 4025) $PN 14
J 0
(810 4035);
DISPLAY 0.617021 (810 4035);
PAINT ORANGE (810 4035);
FORCEPROP 2 LASTPIN (800 4075) $PN 12
J 0
(810 4085);
DISPLAY 0.617021 (810 4085);
PAINT ORANGE (810 4085);
FORCEPROP 2 LASTPIN (800 4125) $PN 10
J 0
(810 4135);
DISPLAY 0.617021 (810 4135);
PAINT ORANGE (810 4135);
FORCEPROP 2 LASTPIN (800 4325) $PN 2
J 0
(810 4335);
DISPLAY 0.617021 (810 4335);
PAINT ORANGE (810 4335);
FORCEPROP 2 LASTPIN (800 4225) $PN 6
J 0
(810 4235);
DISPLAY 0.617021 (810 4235);
PAINT ORANGE (810 4235);
FORCEPROP 2 LASTPIN (800 4175) $PN 8
J 0
(810 4185);
DISPLAY 0.617021 (810 4185);
PAINT ORANGE (810 4185);
FORCEPROP 2 LASTPIN (200 3525) $PN 33
J 2
(190 3535);
DISPLAY 0.617021 (190 3535);
PAINT ORANGE (190 3535);
FORCEPROP 2 LASTPIN (800 2775) $PN 64
J 0
(810 2785);
DISPLAY 0.617021 (810 2785);
PAINT ORANGE (810 2785);
FORCEPROP 2 LASTPIN (800 3625) $PN 30
J 0
(810 3635);
DISPLAY 0.617021 (810 3635);
PAINT ORANGE (810 3635);
FORCEPROP 2 LASTPIN (800 3575) $PN 32
J 0
(810 3585);
DISPLAY 0.617021 (810 3585);
PAINT ORANGE (810 3585);
FORCEPROP 2 LASTPIN (800 3075) $PN 52
J 0
(810 3085);
DISPLAY 0.617021 (810 3085);
PAINT ORANGE (810 3085);
FORCEPROP 2 LASTPIN (800 3125) $PN 50
J 0
(810 3135);
DISPLAY 0.617021 (810 3135);
PAINT ORANGE (810 3135);
FORCEPROP 2 LASTPIN (800 3175) $PN 48
J 0
(810 3185);
DISPLAY 0.617021 (810 3185);
PAINT ORANGE (810 3185);
FORCEPROP 2 LASTPIN (800 3225) $PN 46
J 0
(810 3235);
DISPLAY 0.617021 (810 3235);
PAINT ORANGE (810 3235);
FORCEPROP 2 LASTPIN (200 4325) $PN 1
J 2
(190 4335);
DISPLAY 0.617021 (190 4335);
PAINT ORANGE (190 4335);
FORCEPROP 2 LASTPIN (200 4275) $PN 3
J 2
(190 4285);
DISPLAY 0.617021 (190 4285);
PAINT ORANGE (190 4285);
FORCEPROP 2 LASTPIN (200 4175) $PN 7
J 2
(190 4185);
DISPLAY 0.617021 (190 4185);
PAINT ORANGE (190 4185);
FORCEPROP 2 LASTPIN (200 4125) $PN 9
J 2
(190 4135);
DISPLAY 0.617021 (190 4135);
PAINT ORANGE (190 4135);
FORCEPROP 2 LASTPIN (200 4075) $PN 11
J 2
(190 4085);
DISPLAY 0.617021 (190 4085);
PAINT ORANGE (190 4085);
FORCEPROP 2 LASTPIN (200 4025) $PN 13
J 2
(190 4035);
DISPLAY 0.617021 (190 4035);
PAINT ORANGE (190 4035);
FORCEPROP 2 LASTPIN (200 4225) $PN 5
J 2
(190 4235);
DISPLAY 0.617021 (190 4235);
PAINT ORANGE (190 4235);
FORCEPROP 2 LASTPIN (200 2975) $PN 55
J 2
(190 2985);
DISPLAY 0.617021 (190 2985);
PAINT ORANGE (190 2985);
FORCEPROP 2 LASTPIN (200 3275) $PN 43
J 2
(190 3285);
DISPLAY 0.617021 (190 3285);
PAINT ORANGE (190 3285);
FORCEPROP 2 LASTPIN (800 2175) $PN 88
J 0
(810 2185);
DISPLAY 0.617021 (810 2185);
PAINT ORANGE (810 2185);
FORCEPROP 2 LASTPIN (200 2225) $PN 85
J 2
(190 2235);
DISPLAY 0.617021 (190 2235);
PAINT ORANGE (190 2235);
FORCEPROP 2 LASTPIN (200 3375) $PN 39
J 2
(190 3385);
DISPLAY 0.617021 (190 3385);
PAINT ORANGE (190 3385);
FORCEPROP 2 LASTPIN (200 3425) $PN 37
J 2
(190 3435);
DISPLAY 0.617021 (190 3435);
PAINT ORANGE (190 3435);
FORCEPROP 2 LASTPIN (200 3175) $PN 47
J 2
(190 3185);
DISPLAY 0.617021 (190 3185);
PAINT ORANGE (190 3185);
FORCEPROP 2 LASTPIN (200 3725) $PN 25
J 2
(190 3735);
DISPLAY 0.617021 (190 3735);
PAINT ORANGE (190 3735);
FORCEPROP 2 LASTPIN (200 3675) $PN 27
J 2
(190 3685);
DISPLAY 0.617021 (190 3685);
PAINT ORANGE (190 3685);
FORCEPROP 2 LASTPIN (800 4275) $PN 4
J 0
(810 4285);
DISPLAY 0.617021 (810 4285);
PAINT ORANGE (810 4285);
FORCEPROP 2 LASTPIN (800 3725) $PN 26
J 0
(810 3735);
DISPLAY 0.617021 (810 3735);
PAINT ORANGE (810 3735);
FORCEPROP 2 LASTPIN (800 3975) $PN 16
J 0
(810 3985);
DISPLAY 0.617021 (810 3985);
PAINT ORANGE (810 3985);
FORCEPROP 2 LASTPIN (200 3975) $PN 15
J 2
(190 3985);
DISPLAY 0.617021 (190 3985);
PAINT ORANGE (190 3985);
FORCEPROP 2 LASTPIN (200 3875) $PN 19
J 2
(190 3885);
DISPLAY 0.617021 (190 3885);
PAINT ORANGE (190 3885);
FORCEPROP 2 LASTPIN (200 3775) $PN 23
J 2
(190 3785);
DISPLAY 0.617021 (190 3785);
PAINT ORANGE (190 3785);
FORCEPROP 2 LAST CDS_LIB mstr_sconn
J 0
(500 3075);
PAINT MONO (500 3075);
DISPLAY INVISIBLE (500 3075);
FORCEPROP 1 LAST CDS_LMAN_SYM_OUTLINE -250,1350,250,-1350
J 0
(500 3075);
DISPLAY 0.468085 (500 3075);
PAINT GREEN (500 3075);
DISPLAY INVISIBLE (500 3075);
FORCEPROP 2 LAST CDS_LOCATION J8G1
J 0
(225 4575);
DISPLAY 0.617021 (225 4575);
PAINT AQUA (225 4575);
DISPLAY INVISIBLE (225 4575);
FORCEPROP 1 LAST PACK_TYPE SM
J 0
(250 4625);
PAINT SKYBLUE (250 4625);
DISPLAY INVISIBLE (250 4625);
FORCEPROP 0 LAST ROOM IO_SLOT
J 0
(225 4675);
DISPLAY 1.021277 (225 4675);
PAINT ORANGE (225 4675);
DISPLAY INVISIBLE (225 4675);
FORCEPROP 2 LAST SEC 1
J 0
(550 4575);
DISPLAY 0.680851 (550 4575);
PAINT MONO (550 4575);
DISPLAY INVISIBLE (550 4575);
FORCEPROP 1 LAST PATH I258
J 0
(550 4525);
PAINT GREEN (550 4525);
DISPLAY INVISIBLE (550 4525);
FORCEPROP 2 LAST SEC_TYPE SM
J 0
(550 4575);
DISPLAY 1.021277 (550 4575);
PAINT ORANGE (550 4575);
DISPLAY INVISIBLE (550 4575);
FORCEADD OFFPAGE..1
(-2000 3925);
FORCEPROP 2 LAST $XR0 108 
J 0
(-2282 3925);
DISPLAY 0.638298 (-2282 3925);
PAINT MONO (-2282 3925);
FORCEPROP 1 LAST COMMENT_BODY TRUE
J 0
(-1875 3825);
DISPLAY 0.872340 (-1875 3825);
PAINT GREEN (-1875 3825);
DISPLAY INVISIBLE (-1875 3825);
FORCEPROP 2 LAST CDS_LIB mstr_standard
J 0
(-2000 3925);
PAINT MONO (-2000 3925);
DISPLAY INVISIBLE (-2000 3925);
FORCEPROP 2 LAST PATH I259
J 0
(-1950 4000);
DISPLAY 1.021277 (-1950 4000);
PAINT ORANGE (-1950 4000);
DISPLAY INVISIBLE (-1950 4000);
FORCEPROP 1 LAST OFFPAGE TRUE
J 0
(-1675 3800);
DISPLAY 0.872340 (-1675 3800);
PAINT GREEN (-1675 3800);
DISPLAY INVISIBLE (-1675 3800);
FORCEADD OFFPAGE..3
R 2
(-2000 3975);
FORCEPROP 2 LAST $XR0 108 
J 0
(-2280 3975);
DISPLAY 0.638298 (-2280 3975);
PAINT MONO (-2280 3975);
FORCEPROP 1 LAST OFFPAGE TRUE
J 2
(-2325 3850);
DISPLAY 0.872340 (-2325 3850);
PAINT GREEN (-2325 3850);
DISPLAY INVISIBLE (-2325 3850);
FORCEPROP 2 LAST PATH I260
J 2
(-2050 4050);
DISPLAY 1.021277 (-2050 4050);
PAINT ORANGE (-2050 4050);
DISPLAY INVISIBLE (-2050 4050);
FORCEPROP 1 LAST COMMENT_BODY TRUE
J 2
(-1950 3875);
DISPLAY 0.872340 (-1950 3875);
PAINT GREEN (-1950 3875);
DISPLAY INVISIBLE (-1950 3875);
FORCEPROP 2 LAST CDS_LIB mstr_standard
J 2
(-2000 3975);
PAINT MONO (-2000 3975);
DISPLAY INVISIBLE (-2000 3975);
FORCEADD OFFPAGE..2
R 2
(-2000 3875);
FORCEPROP 2 LAST $XR2 147 
J 0
(-2525 3875);
DISPLAY 0.638298 (-2525 3875);
PAINT MONO (-2525 3875);
FORCEPROP 2 LAST $XR1 119 
J 0
(-2405 3875);
DISPLAY 0.638298 (-2405 3875);
PAINT MONO (-2405 3875);
FORCEPROP 2 LAST $XR0 133 
J 0
(-2285 3875);
DISPLAY 0.638298 (-2285 3875);
PAINT MONO (-2285 3875);
FORCEPROP 1 LAST OFFPAGE TRUE
J 2
(-2325 3750);
DISPLAY 0.872340 (-2325 3750);
PAINT GREEN (-2325 3750);
DISPLAY INVISIBLE (-2325 3750);
FORCEPROP 2 LAST PATH I261
J 2
(-2050 3950);
DISPLAY 1.021277 (-2050 3950);
PAINT ORANGE (-2050 3950);
DISPLAY INVISIBLE (-2050 3950);
FORCEPROP 1 LAST COMMENT_BODY TRUE
J 2
(-1955 3780);
DISPLAY 0.872340 (-1955 3780);
PAINT GREEN (-1955 3780);
DISPLAY INVISIBLE (-1955 3780);
FORCEPROP 2 LAST CDS_LIB mstr_standard
J 2
(-2000 3875);
PAINT MONO (-2000 3875);
DISPLAY INVISIBLE (-2000 3875);
FORCEADD P3V3_STBY..1
(-25 4625);
FORCEPROP 3 LASTPIN (-25 4575) SIG_NAME P3V3_STBY\g
J 0
(-15 4585);
DISPLAY 0.659574 (-15 4585);
PAINT MONO (-15 4585);
DISPLAY INVISIBLE (-15 4585);
FORCEPROP 1 LAST HDL_POWER P3V3_STBY
J 0
(-325 4500);
DISPLAY 0.872340 (-325 4500);
PAINT ORANGE (-325 4500);
DISPLAY INVISIBLE (-325 4500);
FORCEPROP 1 LAST BODY_TYPE PLUMBING
J 0
(-70 4582);
DISPLAY 0.340426 (-70 4582);
PAINT GREEN (-70 4582);
DISPLAY INVISIBLE (-70 4582);
FORCEPROP 1 LAST VOLTAGE 3.3V
J 0
(-70 4582);
DISPLAY 0.340426 (-70 4582);
PAINT SKYBLUE (-70 4582);
DISPLAY INVISIBLE (-70 4582);
FORCEPROP 2 LAST CDS_LIB mstr_symbols
J 0
(-25 4625);
PAINT MONO (-25 4625);
DISPLAY INVISIBLE (-25 4625);
FORCEPROP 1 LAST SIZE 1B
J 0
(20 4647);
DISPLAY 0.340426 (20 4647);
PAINT GREEN (20 4647);
DISPLAY INVISIBLE (20 4647);
FORCEPROP 1 LAST PATH I262
J 0
(20 4627);
DISPLAY 0.340426 (20 4627);
PAINT GREEN (20 4627);
DISPLAY INVISIBLE (20 4627);
FORCEADD OFFPAGE..1
(-2000 3475);
FORCEPROP 2 LAST $XR0 114 
J 0
(-2252 3475);
DISPLAY 0.638298 (-2252 3475);
PAINT MONO (-2252 3475);
FORCEPROP 2 LAST PATH I264
J 0
(-2325 3525);
DISPLAY 1.021277 (-2325 3525);
PAINT ORANGE (-2325 3525);
DISPLAY INVISIBLE (-2325 3525);
FORCEPROP 2 LAST CDS_LIB mstr_standard
J 0
(-2000 3475);
PAINT ORANGE (-2000 3475);
DISPLAY INVISIBLE (-2000 3475);
FORCEPROP 1 LAST COMMENT_BODY TRUE
J 0
(-1875 3375);
DISPLAY 0.872340 (-1875 3375);
PAINT GREEN (-1875 3375);
DISPLAY INVISIBLE (-1875 3375);
FORCEPROP 1 LAST OFFPAGE TRUE
J 0
(-1675 3350);
DISPLAY 0.872340 (-1675 3350);
PAINT GREEN (-1675 3350);
DISPLAY INVISIBLE (-1675 3350);
FORCEADD OFFPAGE..1
(-2000 3425);
FORCEPROP 2 LAST $XR0 114 
J 0
(-2252 3425);
DISPLAY 0.638298 (-2252 3425);
PAINT MONO (-2252 3425);
FORCEPROP 1 LAST OFFPAGE TRUE
J 0
(-1675 3300);
DISPLAY 0.872340 (-1675 3300);
PAINT GREEN (-1675 3300);
DISPLAY INVISIBLE (-1675 3300);
FORCEPROP 1 LAST COMMENT_BODY TRUE
J 0
(-1875 3325);
DISPLAY 0.872340 (-1875 3325);
PAINT GREEN (-1875 3325);
DISPLAY INVISIBLE (-1875 3325);
FORCEPROP 2 LAST CDS_LIB mstr_standard
J 0
(-2000 3425);
PAINT ORANGE (-2000 3425);
DISPLAY INVISIBLE (-2000 3425);
FORCEPROP 2 LAST PATH I265
J 0
(-2325 3475);
DISPLAY 1.021277 (-2325 3475);
PAINT ORANGE (-2325 3475);
DISPLAY INVISIBLE (-2325 3475);
FORCEADD OFFPAGE..1
(-2000 3225);
FORCEPROP 2 LAST $XR0 114 
J 0
(-2252 3225);
DISPLAY 0.638298 (-2252 3225);
PAINT MONO (-2252 3225);
FORCEPROP 2 LAST CDS_LIB mstr_standard
J 0
(-2000 3225);
PAINT ORANGE (-2000 3225);
DISPLAY INVISIBLE (-2000 3225);
FORCEPROP 1 LAST COMMENT_BODY TRUE
J 0
(-1875 3125);
DISPLAY 0.872340 (-1875 3125);
PAINT GREEN (-1875 3125);
DISPLAY INVISIBLE (-1875 3125);
FORCEPROP 2 LAST PATH I266
J 0
(-1950 3300);
DISPLAY 1.021277 (-1950 3300);
PAINT ORANGE (-1950 3300);
DISPLAY INVISIBLE (-1950 3300);
FORCEPROP 1 LAST OFFPAGE TRUE
J 0
(-1675 3100);
DISPLAY 0.872340 (-1675 3100);
PAINT GREEN (-1675 3100);
DISPLAY INVISIBLE (-1675 3100);
FORCEADD OFFPAGE..1
(-2000 3175);
FORCEPROP 2 LAST $XR0 114 
J 0
(-2252 3175);
DISPLAY 0.638298 (-2252 3175);
PAINT MONO (-2252 3175);
FORCEPROP 1 LAST COMMENT_BODY TRUE
J 0
(-1875 3075);
DISPLAY 0.872340 (-1875 3075);
PAINT GREEN (-1875 3075);
DISPLAY INVISIBLE (-1875 3075);
FORCEPROP 2 LAST PATH I267
J 0
(-1950 3250);
DISPLAY 1.021277 (-1950 3250);
PAINT ORANGE (-1950 3250);
DISPLAY INVISIBLE (-1950 3250);
FORCEPROP 2 LAST CDS_LIB mstr_standard
J 0
(-2000 3175);
PAINT ORANGE (-2000 3175);
DISPLAY INVISIBLE (-2000 3175);
FORCEPROP 1 LAST OFFPAGE TRUE
J 0
(-1675 3050);
DISPLAY 0.872340 (-1675 3050);
PAINT GREEN (-1675 3050);
DISPLAY INVISIBLE (-1675 3050);
FORCEADD OFFPAGE..1
(-2000 3125);
FORCEPROP 2 LAST $XR0 244 
J 0
(-2252 3125);
DISPLAY 0.638298 (-2252 3125);
PAINT MONO (-2252 3125);
FORCEPROP 2 LAST PATH I269
J 0
(-1950 3200);
DISPLAY 1.021277 (-1950 3200);
PAINT ORANGE (-1950 3200);
DISPLAY INVISIBLE (-1950 3200);
FORCEPROP 2 LAST CDS_LIB mstr_standard
J 0
(-2000 3125);
PAINT MONO (-2000 3125);
DISPLAY INVISIBLE (-2000 3125);
FORCEPROP 1 LAST OFFPAGE TRUE
J 0
(-1675 3000);
DISPLAY 0.872340 (-1675 3000);
PAINT GREEN (-1675 3000);
DISPLAY INVISIBLE (-1675 3000);
FORCEPROP 1 LAST COMMENT_BODY TRUE
J 0
(-1875 3025);
DISPLAY 0.872340 (-1875 3025);
PAINT GREEN (-1875 3025);
DISPLAY INVISIBLE (-1875 3025);
FORCEADD OFFPAGE..1
(-2000 3075);
FORCEPROP 2 LAST $XR0 244 
J 0
(-2252 3075);
DISPLAY 0.638298 (-2252 3075);
PAINT MONO (-2252 3075);
FORCEPROP 1 LAST COMMENT_BODY TRUE
J 0
(-1875 2975);
DISPLAY 0.872340 (-1875 2975);
PAINT GREEN (-1875 2975);
DISPLAY INVISIBLE (-1875 2975);
FORCEPROP 1 LAST OFFPAGE TRUE
J 0
(-1675 2950);
DISPLAY 0.872340 (-1675 2950);
PAINT GREEN (-1675 2950);
DISPLAY INVISIBLE (-1675 2950);
FORCEPROP 2 LAST CDS_LIB mstr_standard
J 0
(-2000 3075);
PAINT MONO (-2000 3075);
DISPLAY INVISIBLE (-2000 3075);
FORCEPROP 2 LAST PATH I270
J 0
(-1950 3150);
DISPLAY 1.021277 (-1950 3150);
PAINT ORANGE (-1950 3150);
DISPLAY INVISIBLE (-1950 3150);
FORCEADD TAP..1
R 2
(-550 3075);
FORCEPROP 3 LASTPIN (-500 3075) SIG_NAME P3E_CPU0_PE1_PCH_CON_TXN<15>
J 0
(-490 3085);
DISPLAY 0.659574 (-490 3085);
PAINT MONO (-490 3085);
DISPLAY INVISIBLE (-490 3085);
FORCEPROP 1 LASTPIN (-500 3075) BN 15
J 2
(-488 3083);
DISPLAY 0.617021 (-488 3083);
PAINT GREEN (-488 3083);
FORCEPROP 2 LAST CDS_LIB mstr_standard
J 0
(-550 3075);
PAINT MONO (-550 3075);
DISPLAY INVISIBLE (-550 3075);
FORCEPROP 1 LAST BODY_TYPE PLUMBING
J 2
(-725 3125);
DISPLAY 0.872340 (-725 3125);
PAINT GREEN (-725 3125);
DISPLAY INVISIBLE (-725 3125);
FORCEPROP 1 LAST PATH I271
J 2
(-548 3075);
DISPLAY 0.872340 (-548 3075);
PAINT GREEN (-548 3075);
DISPLAY INVISIBLE (-548 3075);
FORCEPROP 1 LAST HDL_TAP TRUE
J 2
(-1050 2950);
DISPLAY 0.872340 (-1050 2950);
PAINT ORANGE (-1050 2950);
DISPLAY INVISIBLE (-1050 2950);
FORCEADD TAP..1
R 2
(-750 3025);
FORCEPROP 3 LASTPIN (-700 3025) SIG_NAME P3E_CPU0_PE1_PCH_CON_TXP<15>
J 0
(-690 3035);
DISPLAY 0.659574 (-690 3035);
PAINT MONO (-690 3035);
DISPLAY INVISIBLE (-690 3035);
FORCEPROP 1 LASTPIN (-700 3025) BN 15
J 2
(-688 3033);
DISPLAY 0.617021 (-688 3033);
PAINT GREEN (-688 3033);
FORCEPROP 1 LAST BODY_TYPE PLUMBING
J 2
(-925 3075);
DISPLAY 0.872340 (-925 3075);
PAINT GREEN (-925 3075);
DISPLAY INVISIBLE (-925 3075);
FORCEPROP 1 LAST PATH I272
J 2
(-748 3025);
DISPLAY 0.872340 (-748 3025);
PAINT GREEN (-748 3025);
DISPLAY INVISIBLE (-748 3025);
FORCEPROP 2 LAST CDS_LIB mstr_standard
J 0
(-750 3025);
PAINT MONO (-750 3025);
DISPLAY INVISIBLE (-750 3025);
FORCEPROP 1 LAST HDL_TAP TRUE
J 2
(-1250 2900);
DISPLAY 0.872340 (-1250 2900);
PAINT ORANGE (-1250 2900);
DISPLAY INVISIBLE (-1250 2900);
FORCEADD TAP..1
R 2
(-750 2925);
FORCEPROP 3 LASTPIN (-700 2925) SIG_NAME P3E_CPU0_PE1_PCH_CON_TXP<14>
J 0
(-690 2935);
DISPLAY 0.659574 (-690 2935);
PAINT MONO (-690 2935);
DISPLAY INVISIBLE (-690 2935);
FORCEPROP 1 LASTPIN (-700 2925) BN 14
J 2
(-688 2933);
DISPLAY 0.617021 (-688 2933);
PAINT GREEN (-688 2933);
FORCEPROP 1 LAST HDL_TAP TRUE
J 2
(-1250 2800);
DISPLAY 0.872340 (-1250 2800);
PAINT ORANGE (-1250 2800);
DISPLAY INVISIBLE (-1250 2800);
FORCEPROP 1 LAST BODY_TYPE PLUMBING
J 2
(-925 2975);
DISPLAY 0.872340 (-925 2975);
PAINT GREEN (-925 2975);
DISPLAY INVISIBLE (-925 2975);
FORCEPROP 1 LAST PATH I273
J 2
(-748 2925);
DISPLAY 0.872340 (-748 2925);
PAINT GREEN (-748 2925);
DISPLAY INVISIBLE (-748 2925);
FORCEPROP 2 LAST CDS_LIB mstr_standard
J 0
(-750 2925);
PAINT MONO (-750 2925);
DISPLAY INVISIBLE (-750 2925);
FORCEADD TAP..1
R 2
(-550 2875);
FORCEPROP 3 LASTPIN (-500 2875) SIG_NAME P3E_CPU0_PE1_PCH_CON_TXN<14>
J 0
(-490 2885);
DISPLAY 0.659574 (-490 2885);
PAINT MONO (-490 2885);
DISPLAY INVISIBLE (-490 2885);
FORCEPROP 1 LASTPIN (-500 2875) BN 14
J 2
(-488 2883);
DISPLAY 0.617021 (-488 2883);
PAINT GREEN (-488 2883);
FORCEPROP 1 LAST HDL_TAP TRUE
J 2
(-1050 2750);
DISPLAY 0.872340 (-1050 2750);
PAINT ORANGE (-1050 2750);
DISPLAY INVISIBLE (-1050 2750);
FORCEPROP 1 LAST BODY_TYPE PLUMBING
J 2
(-725 2925);
DISPLAY 0.872340 (-725 2925);
PAINT GREEN (-725 2925);
DISPLAY INVISIBLE (-725 2925);
FORCEPROP 2 LAST CDS_LIB mstr_standard
J 0
(-550 2875);
PAINT MONO (-550 2875);
DISPLAY INVISIBLE (-550 2875);
FORCEPROP 1 LAST PATH I274
J 2
(-548 2875);
DISPLAY 0.872340 (-548 2875);
PAINT GREEN (-548 2875);
DISPLAY INVISIBLE (-548 2875);
FORCEADD TAP..1
R 2
(-750 2625);
FORCEPROP 3 LASTPIN (-700 2625) SIG_NAME P3E_CPU0_PE1_PCH_CON_TXP<13>
J 0
(-690 2635);
DISPLAY 0.659574 (-690 2635);
PAINT MONO (-690 2635);
DISPLAY INVISIBLE (-690 2635);
FORCEPROP 1 LASTPIN (-700 2625) BN 13
J 2
(-688 2633);
DISPLAY 0.617021 (-688 2633);
PAINT GREEN (-688 2633);
FORCEPROP 1 LAST HDL_TAP TRUE
J 2
(-1250 2500);
DISPLAY 0.872340 (-1250 2500);
PAINT ORANGE (-1250 2500);
DISPLAY INVISIBLE (-1250 2500);
FORCEPROP 1 LAST BODY_TYPE PLUMBING
J 2
(-925 2675);
DISPLAY 0.872340 (-925 2675);
PAINT GREEN (-925 2675);
DISPLAY INVISIBLE (-925 2675);
FORCEPROP 2 LAST CDS_LIB mstr_standard
J 0
(-750 2625);
PAINT MONO (-750 2625);
DISPLAY INVISIBLE (-750 2625);
FORCEPROP 1 LAST PATH I275
J 2
(-748 2625);
DISPLAY 0.872340 (-748 2625);
PAINT GREEN (-748 2625);
DISPLAY INVISIBLE (-748 2625);
FORCEADD TAP..1
R 2
(-550 2675);
FORCEPROP 3 LASTPIN (-500 2675) SIG_NAME P3E_CPU0_PE1_PCH_CON_TXN<13>
J 0
(-490 2685);
DISPLAY 0.659574 (-490 2685);
PAINT MONO (-490 2685);
DISPLAY INVISIBLE (-490 2685);
FORCEPROP 1 LASTPIN (-500 2675) BN 13
J 2
(-488 2683);
DISPLAY 0.617021 (-488 2683);
PAINT GREEN (-488 2683);
FORCEPROP 1 LAST HDL_TAP TRUE
J 2
(-1050 2550);
DISPLAY 0.872340 (-1050 2550);
PAINT ORANGE (-1050 2550);
DISPLAY INVISIBLE (-1050 2550);
FORCEPROP 1 LAST BODY_TYPE PLUMBING
J 2
(-725 2725);
DISPLAY 0.872340 (-725 2725);
PAINT GREEN (-725 2725);
DISPLAY INVISIBLE (-725 2725);
FORCEPROP 2 LAST CDS_LIB mstr_standard
J 0
(-550 2675);
PAINT MONO (-550 2675);
DISPLAY INVISIBLE (-550 2675);
FORCEPROP 1 LAST PATH I276
J 2
(-548 2675);
DISPLAY 0.872340 (-548 2675);
PAINT GREEN (-548 2675);
DISPLAY INVISIBLE (-548 2675);
FORCEADD TAP..1
R 2
(-750 2475);
FORCEPROP 3 LASTPIN (-700 2475) SIG_NAME P3E_CPU0_PE1_PCH_CON_TXP<12>
J 0
(-690 2485);
DISPLAY 0.659574 (-690 2485);
PAINT MONO (-690 2485);
DISPLAY INVISIBLE (-690 2485);
FORCEPROP 1 LASTPIN (-700 2475) BN 12
J 2
(-688 2483);
DISPLAY 0.617021 (-688 2483);
PAINT GREEN (-688 2483);
FORCEPROP 1 LAST BODY_TYPE PLUMBING
J 2
(-925 2525);
DISPLAY 0.872340 (-925 2525);
PAINT GREEN (-925 2525);
DISPLAY INVISIBLE (-925 2525);
FORCEPROP 1 LAST PATH I277
J 2
(-748 2475);
DISPLAY 0.872340 (-748 2475);
PAINT GREEN (-748 2475);
DISPLAY INVISIBLE (-748 2475);
FORCEPROP 2 LAST CDS_LIB mstr_standard
J 0
(-750 2475);
PAINT MONO (-750 2475);
DISPLAY INVISIBLE (-750 2475);
FORCEPROP 1 LAST HDL_TAP TRUE
J 2
(-1250 2350);
DISPLAY 0.872340 (-1250 2350);
PAINT ORANGE (-1250 2350);
DISPLAY INVISIBLE (-1250 2350);
FORCEADD TAP..1
R 2
(-550 2525);
FORCEPROP 3 LASTPIN (-500 2525) SIG_NAME P3E_CPU0_PE1_PCH_CON_TXN<12>
J 0
(-490 2535);
DISPLAY 0.659574 (-490 2535);
PAINT MONO (-490 2535);
DISPLAY INVISIBLE (-490 2535);
FORCEPROP 1 LASTPIN (-500 2525) BN 12
J 2
(-488 2533);
DISPLAY 0.617021 (-488 2533);
PAINT GREEN (-488 2533);
FORCEPROP 1 LAST HDL_TAP TRUE
J 2
(-1050 2400);
DISPLAY 0.872340 (-1050 2400);
PAINT ORANGE (-1050 2400);
DISPLAY INVISIBLE (-1050 2400);
FORCEPROP 1 LAST PATH I278
J 2
(-548 2525);
DISPLAY 0.872340 (-548 2525);
PAINT GREEN (-548 2525);
DISPLAY INVISIBLE (-548 2525);
FORCEPROP 2 LAST CDS_LIB mstr_standard
J 0
(-550 2525);
PAINT MONO (-550 2525);
DISPLAY INVISIBLE (-550 2525);
FORCEPROP 1 LAST BODY_TYPE PLUMBING
J 2
(-725 2575);
DISPLAY 0.872340 (-725 2575);
PAINT GREEN (-725 2575);
DISPLAY INVISIBLE (-725 2575);
FORCEADD TAP..1
R 2
(-750 2325);
FORCEPROP 3 LASTPIN (-700 2325) SIG_NAME P3E_CPU0_PE1_PCH_CON_TXP<11>
J 0
(-690 2335);
DISPLAY 0.659574 (-690 2335);
PAINT MONO (-690 2335);
DISPLAY INVISIBLE (-690 2335);
FORCEPROP 1 LASTPIN (-700 2325) BN 11
J 2
(-688 2333);
DISPLAY 0.617021 (-688 2333);
PAINT GREEN (-688 2333);
FORCEPROP 1 LAST HDL_TAP TRUE
J 2
(-1250 2200);
DISPLAY 0.872340 (-1250 2200);
PAINT ORANGE (-1250 2200);
DISPLAY INVISIBLE (-1250 2200);
FORCEPROP 1 LAST BODY_TYPE PLUMBING
J 2
(-925 2375);
DISPLAY 0.872340 (-925 2375);
PAINT GREEN (-925 2375);
DISPLAY INVISIBLE (-925 2375);
FORCEPROP 2 LAST CDS_LIB mstr_standard
J 0
(-750 2325);
PAINT MONO (-750 2325);
DISPLAY INVISIBLE (-750 2325);
FORCEPROP 1 LAST PATH I279
J 2
(-748 2325);
DISPLAY 0.872340 (-748 2325);
PAINT GREEN (-748 2325);
DISPLAY INVISIBLE (-748 2325);
FORCEADD TAP..1
R 2
(-550 2375);
FORCEPROP 3 LASTPIN (-500 2375) SIG_NAME P3E_CPU0_PE1_PCH_CON_TXN<11>
J 0
(-490 2385);
DISPLAY 0.659574 (-490 2385);
PAINT MONO (-490 2385);
DISPLAY INVISIBLE (-490 2385);
FORCEPROP 1 LASTPIN (-500 2375) BN 11
J 2
(-488 2383);
DISPLAY 0.617021 (-488 2383);
PAINT GREEN (-488 2383);
FORCEPROP 1 LAST HDL_TAP TRUE
J 2
(-1050 2250);
DISPLAY 0.872340 (-1050 2250);
PAINT ORANGE (-1050 2250);
DISPLAY INVISIBLE (-1050 2250);
FORCEPROP 1 LAST BODY_TYPE PLUMBING
J 2
(-725 2425);
DISPLAY 0.872340 (-725 2425);
PAINT GREEN (-725 2425);
DISPLAY INVISIBLE (-725 2425);
FORCEPROP 2 LAST CDS_LIB mstr_standard
J 0
(-550 2375);
PAINT MONO (-550 2375);
DISPLAY INVISIBLE (-550 2375);
FORCEPROP 1 LAST PATH I280
J 2
(-548 2375);
DISPLAY 0.872340 (-548 2375);
PAINT GREEN (-548 2375);
DISPLAY INVISIBLE (-548 2375);
FORCEADD TAP..1
R 2
(-750 2175);
FORCEPROP 3 LASTPIN (-700 2175) SIG_NAME P3E_CPU0_PE1_PCH_CON_TXP<10>
J 0
(-690 2185);
DISPLAY 0.659574 (-690 2185);
PAINT MONO (-690 2185);
DISPLAY INVISIBLE (-690 2185);
FORCEPROP 1 LASTPIN (-700 2175) BN 10
J 2
(-688 2183);
DISPLAY 0.617021 (-688 2183);
PAINT GREEN (-688 2183);
FORCEPROP 1 LAST HDL_TAP TRUE
J 2
(-1250 2050);
DISPLAY 0.872340 (-1250 2050);
PAINT ORANGE (-1250 2050);
DISPLAY INVISIBLE (-1250 2050);
FORCEPROP 1 LAST BODY_TYPE PLUMBING
J 2
(-925 2225);
DISPLAY 0.872340 (-925 2225);
PAINT GREEN (-925 2225);
DISPLAY INVISIBLE (-925 2225);
FORCEPROP 1 LAST PATH I281
J 2
(-748 2175);
DISPLAY 0.872340 (-748 2175);
PAINT GREEN (-748 2175);
DISPLAY INVISIBLE (-748 2175);
FORCEPROP 2 LAST CDS_LIB mstr_standard
J 0
(-750 2175);
PAINT MONO (-750 2175);
DISPLAY INVISIBLE (-750 2175);
FORCEADD TAP..1
R 2
(-550 2225);
FORCEPROP 3 LASTPIN (-500 2225) SIG_NAME P3E_CPU0_PE1_PCH_CON_TXN<10>
J 0
(-490 2235);
DISPLAY 0.659574 (-490 2235);
PAINT MONO (-490 2235);
DISPLAY INVISIBLE (-490 2235);
FORCEPROP 1 LASTPIN (-500 2225) BN 10
J 2
(-488 2233);
DISPLAY 0.617021 (-488 2233);
PAINT GREEN (-488 2233);
FORCEPROP 1 LAST HDL_TAP TRUE
J 2
(-1050 2100);
DISPLAY 0.872340 (-1050 2100);
PAINT ORANGE (-1050 2100);
DISPLAY INVISIBLE (-1050 2100);
FORCEPROP 2 LAST CDS_LIB mstr_standard
J 0
(-550 2225);
PAINT MONO (-550 2225);
DISPLAY INVISIBLE (-550 2225);
FORCEPROP 1 LAST PATH I282
J 2
(-548 2225);
DISPLAY 0.872340 (-548 2225);
PAINT GREEN (-548 2225);
DISPLAY INVISIBLE (-548 2225);
FORCEPROP 1 LAST BODY_TYPE PLUMBING
J 2
(-725 2275);
DISPLAY 0.872340 (-725 2275);
PAINT GREEN (-725 2275);
DISPLAY INVISIBLE (-725 2275);
FORCEADD TAP..1
R 2
(-750 2025);
FORCEPROP 3 LASTPIN (-700 2025) SIG_NAME P3E_CPU0_PE1_PCH_CON_TXP<9>
J 0
(-690 2035);
DISPLAY 0.659574 (-690 2035);
PAINT MONO (-690 2035);
DISPLAY INVISIBLE (-690 2035);
FORCEPROP 1 LASTPIN (-700 2025) BN 9
J 2
(-688 2033);
DISPLAY 0.617021 (-688 2033);
PAINT GREEN (-688 2033);
FORCEPROP 1 LAST HDL_TAP TRUE
J 2
(-1250 1900);
DISPLAY 0.872340 (-1250 1900);
PAINT ORANGE (-1250 1900);
DISPLAY INVISIBLE (-1250 1900);
FORCEPROP 1 LAST PATH I283
J 2
(-748 2025);
DISPLAY 0.872340 (-748 2025);
PAINT GREEN (-748 2025);
DISPLAY INVISIBLE (-748 2025);
FORCEPROP 2 LAST CDS_LIB mstr_standard
J 0
(-750 2025);
PAINT MONO (-750 2025);
DISPLAY INVISIBLE (-750 2025);
FORCEPROP 1 LAST BODY_TYPE PLUMBING
J 2
(-925 2075);
DISPLAY 0.872340 (-925 2075);
PAINT GREEN (-925 2075);
DISPLAY INVISIBLE (-925 2075);
FORCEADD TAP..1
R 2
(-550 2075);
FORCEPROP 3 LASTPIN (-500 2075) SIG_NAME P3E_CPU0_PE1_PCH_CON_TXN<9>
J 0
(-490 2085);
DISPLAY 0.659574 (-490 2085);
PAINT MONO (-490 2085);
DISPLAY INVISIBLE (-490 2085);
FORCEPROP 1 LASTPIN (-500 2075) BN 9
J 2
(-488 2083);
DISPLAY 0.617021 (-488 2083);
PAINT GREEN (-488 2083);
FORCEPROP 1 LAST HDL_TAP TRUE
J 2
(-1050 1950);
DISPLAY 0.872340 (-1050 1950);
PAINT ORANGE (-1050 1950);
DISPLAY INVISIBLE (-1050 1950);
FORCEPROP 1 LAST BODY_TYPE PLUMBING
J 2
(-725 2125);
DISPLAY 0.872340 (-725 2125);
PAINT GREEN (-725 2125);
DISPLAY INVISIBLE (-725 2125);
FORCEPROP 2 LAST CDS_LIB mstr_standard
J 0
(-550 2075);
PAINT MONO (-550 2075);
DISPLAY INVISIBLE (-550 2075);
FORCEPROP 1 LAST PATH I284
J 2
(-548 2075);
DISPLAY 0.872340 (-548 2075);
PAINT GREEN (-548 2075);
DISPLAY INVISIBLE (-548 2075);
FORCEADD TAP..1
R 2
(-750 1875);
FORCEPROP 3 LASTPIN (-700 1875) SIG_NAME P3E_CPU0_PE1_PCH_CON_TXP<8>
J 0
(-690 1885);
DISPLAY 0.659574 (-690 1885);
PAINT MONO (-690 1885);
DISPLAY INVISIBLE (-690 1885);
FORCEPROP 1 LASTPIN (-700 1875) BN 8
J 2
(-688 1883);
DISPLAY 0.617021 (-688 1883);
PAINT GREEN (-688 1883);
FORCEPROP 1 LAST HDL_TAP TRUE
J 2
(-1250 1750);
DISPLAY 0.872340 (-1250 1750);
PAINT ORANGE (-1250 1750);
DISPLAY INVISIBLE (-1250 1750);
FORCEPROP 1 LAST BODY_TYPE PLUMBING
J 2
(-925 1925);
DISPLAY 0.872340 (-925 1925);
PAINT GREEN (-925 1925);
DISPLAY INVISIBLE (-925 1925);
FORCEPROP 1 LAST PATH I285
J 2
(-748 1875);
DISPLAY 0.872340 (-748 1875);
PAINT GREEN (-748 1875);
DISPLAY INVISIBLE (-748 1875);
FORCEPROP 2 LAST CDS_LIB mstr_standard
J 0
(-750 1875);
PAINT MONO (-750 1875);
DISPLAY INVISIBLE (-750 1875);
FORCEADD TAP..1
R 2
(-550 1925);
FORCEPROP 3 LASTPIN (-500 1925) SIG_NAME P3E_CPU0_PE1_PCH_CON_TXN<8>
J 0
(-490 1935);
DISPLAY 0.659574 (-490 1935);
PAINT MONO (-490 1935);
DISPLAY INVISIBLE (-490 1935);
FORCEPROP 1 LASTPIN (-500 1925) BN 8
J 2
(-488 1933);
DISPLAY 0.617021 (-488 1933);
PAINT GREEN (-488 1933);
FORCEPROP 1 LAST HDL_TAP TRUE
J 2
(-1050 1800);
DISPLAY 0.872340 (-1050 1800);
PAINT ORANGE (-1050 1800);
DISPLAY INVISIBLE (-1050 1800);
FORCEPROP 1 LAST BODY_TYPE PLUMBING
J 2
(-725 1975);
DISPLAY 0.872340 (-725 1975);
PAINT GREEN (-725 1975);
DISPLAY INVISIBLE (-725 1975);
FORCEPROP 1 LAST PATH I286
J 2
(-548 1925);
DISPLAY 0.872340 (-548 1925);
PAINT GREEN (-548 1925);
DISPLAY INVISIBLE (-548 1925);
FORCEPROP 2 LAST CDS_LIB mstr_standard
J 0
(-550 1925);
PAINT MONO (-550 1925);
DISPLAY INVISIBLE (-550 1925);
FORCEADD OFFPAGE..4
(2850 3475);
FORCEPROP 2 LAST $XR0 114 
J 0
(3036 3475);
DISPLAY 0.638298 (3036 3475);
PAINT MONO (3036 3475);
FORCEPROP 1 LAST OFFPAGE TRUE
J 0
(3175 3350);
PAINT GREEN (3175 3350);
DISPLAY INVISIBLE (3175 3350);
FORCEPROP 1 LAST COMMENT_BODY TRUE
J 0
(2825 3375);
DISPLAY 0.638298 (2825 3375);
PAINT GREEN (2825 3375);
DISPLAY INVISIBLE (2825 3375);
FORCEPROP 2 LAST PATH I287
J 0
(3025 3550);
DISPLAY 1.021277 (3025 3550);
PAINT ORANGE (3025 3550);
DISPLAY INVISIBLE (3025 3550);
FORCEPROP 2 LAST CDS_LIB mstr_standard
J 0
(2850 3475);
PAINT MONO (2850 3475);
DISPLAY INVISIBLE (2850 3475);
FORCEADD OFFPAGE..4
(2850 3425);
FORCEPROP 2 LAST $XR0 114 
J 0
(3036 3425);
DISPLAY 0.638298 (3036 3425);
PAINT MONO (3036 3425);
FORCEPROP 1 LAST OFFPAGE TRUE
J 0
(3175 3300);
PAINT GREEN (3175 3300);
DISPLAY INVISIBLE (3175 3300);
FORCEPROP 2 LAST PATH I288
J 0
(3025 3500);
DISPLAY 1.021277 (3025 3500);
PAINT ORANGE (3025 3500);
DISPLAY INVISIBLE (3025 3500);
FORCEPROP 2 LAST CDS_LIB mstr_standard
J 0
(2850 3425);
PAINT MONO (2850 3425);
DISPLAY INVISIBLE (2850 3425);
FORCEPROP 1 LAST COMMENT_BODY TRUE
J 0
(2825 3325);
DISPLAY 0.638298 (2825 3325);
PAINT GREEN (2825 3325);
DISPLAY INVISIBLE (2825 3325);
FORCEADD OFFPAGE..4
(2850 3325);
FORCEPROP 2 LAST $XR0 114 
J 0
(3036 3325);
DISPLAY 0.638298 (3036 3325);
PAINT MONO (3036 3325);
FORCEPROP 1 LAST OFFPAGE TRUE
J 0
(3175 3200);
PAINT GREEN (3175 3200);
DISPLAY INVISIBLE (3175 3200);
FORCEPROP 2 LAST PATH I289
J 0
(3025 3400);
DISPLAY 1.021277 (3025 3400);
PAINT ORANGE (3025 3400);
DISPLAY INVISIBLE (3025 3400);
FORCEPROP 2 LAST CDS_LIB mstr_standard
J 0
(2850 3325);
PAINT MONO (2850 3325);
DISPLAY INVISIBLE (2850 3325);
FORCEPROP 1 LAST COMMENT_BODY TRUE
J 0
(2825 3225);
DISPLAY 0.638298 (2825 3225);
PAINT GREEN (2825 3225);
DISPLAY INVISIBLE (2825 3225);
FORCEADD OFFPAGE..4
(2850 3275);
FORCEPROP 2 LAST $XR0 114 
J 0
(3036 3275);
DISPLAY 0.638298 (3036 3275);
PAINT MONO (3036 3275);
FORCEPROP 1 LAST OFFPAGE TRUE
J 0
(3175 3150);
PAINT GREEN (3175 3150);
DISPLAY INVISIBLE (3175 3150);
FORCEPROP 2 LAST PATH I290
J 0
(3025 3350);
DISPLAY 1.021277 (3025 3350);
PAINT ORANGE (3025 3350);
DISPLAY INVISIBLE (3025 3350);
FORCEPROP 2 LAST CDS_LIB mstr_standard
J 0
(2850 3275);
PAINT MONO (2850 3275);
DISPLAY INVISIBLE (2850 3275);
FORCEPROP 1 LAST COMMENT_BODY TRUE
J 0
(2825 3175);
DISPLAY 0.638298 (2825 3175);
PAINT GREEN (2825 3175);
DISPLAY INVISIBLE (2825 3175);
FORCEADD OFFPAGE..4
(2850 3125);
FORCEPROP 2 LAST $XR0 114 
J 0
(3036 3125);
DISPLAY 0.638298 (3036 3125);
PAINT MONO (3036 3125);
FORCEPROP 2 LAST PATH I291
J 0
(3025 3200);
DISPLAY 1.021277 (3025 3200);
PAINT ORANGE (3025 3200);
DISPLAY INVISIBLE (3025 3200);
FORCEPROP 2 LAST CDS_LIB mstr_standard
J 0
(2850 3125);
PAINT MONO (2850 3125);
DISPLAY INVISIBLE (2850 3125);
FORCEPROP 1 LAST OFFPAGE TRUE
J 0
(3175 3000);
PAINT GREEN (3175 3000);
DISPLAY INVISIBLE (3175 3000);
FORCEPROP 1 LAST COMMENT_BODY TRUE
J 0
(2825 3025);
DISPLAY 0.638298 (2825 3025);
PAINT GREEN (2825 3025);
DISPLAY INVISIBLE (2825 3025);
FORCEADD OFFPAGE..4
(2850 3175);
FORCEPROP 2 LAST $XR0 114 
J 0
(3036 3175);
DISPLAY 0.638298 (3036 3175);
PAINT MONO (3036 3175);
FORCEPROP 1 LAST OFFPAGE TRUE
J 0
(3175 3050);
PAINT GREEN (3175 3050);
DISPLAY INVISIBLE (3175 3050);
FORCEPROP 1 LAST COMMENT_BODY TRUE
J 0
(2825 3075);
DISPLAY 0.638298 (2825 3075);
PAINT GREEN (2825 3075);
DISPLAY INVISIBLE (2825 3075);
FORCEPROP 2 LAST CDS_LIB mstr_standard
J 0
(2850 3175);
PAINT MONO (2850 3175);
DISPLAY INVISIBLE (2850 3175);
FORCEPROP 2 LAST PATH I292
J 0
(3025 3250);
DISPLAY 1.021277 (3025 3250);
PAINT ORANGE (3025 3250);
DISPLAY INVISIBLE (3025 3250);
FORCEADD OFFPAGE..2
(2850 3075);
FORCEPROP 2 LAST $XR1 244 
J 0
(3159 3075);
DISPLAY 0.638298 (3159 3075);
PAINT MONO (3159 3075);
FORCEPROP 2 LAST $XR0 109 
J 0
(3039 3075);
DISPLAY 0.638298 (3039 3075);
PAINT MONO (3039 3075);
FORCEPROP 1 LAST COMMENT_BODY TRUE
J 0
(2805 2980);
DISPLAY 0.872340 (2805 2980);
PAINT GREEN (2805 2980);
DISPLAY INVISIBLE (2805 2980);
FORCEPROP 1 LAST OFFPAGE TRUE
J 0
(3175 2950);
DISPLAY 0.872340 (3175 2950);
PAINT GREEN (3175 2950);
DISPLAY INVISIBLE (3175 2950);
FORCEPROP 2 LAST CDS_LIB mstr_standard
J 0
(2850 3075);
PAINT MONO (2850 3075);
DISPLAY INVISIBLE (2850 3075);
FORCEPROP 2 LAST PATH I293
J 0
(3025 3150);
DISPLAY 1.021277 (3025 3150);
PAINT ORANGE (3025 3150);
DISPLAY INVISIBLE (3025 3150);
FORCEADD OFFPAGE..2
(2850 2975);
FORCEPROP 2 LAST $XR0 244 
J 0
(3039 2975);
DISPLAY 0.638298 (3039 2975);
PAINT MONO (3039 2975);
FORCEPROP 1 LAST COMMENT_BODY TRUE
J 0
(2805 2880);
DISPLAY 0.872340 (2805 2880);
PAINT GREEN (2805 2880);
DISPLAY INVISIBLE (2805 2880);
FORCEPROP 2 LAST CDS_LIB mstr_standard
J 0
(2850 2975);
PAINT MONO (2850 2975);
DISPLAY INVISIBLE (2850 2975);
FORCEPROP 1 LAST OFFPAGE TRUE
J 0
(3175 2850);
DISPLAY 0.872340 (3175 2850);
PAINT GREEN (3175 2850);
DISPLAY INVISIBLE (3175 2850);
FORCEPROP 2 LAST PATH I294
J 0
(3025 3050);
DISPLAY 1.021277 (3025 3050);
PAINT ORANGE (3025 3050);
DISPLAY INVISIBLE (3025 3050);
FORCEADD TAP..1
(1350 2975);
FORCEPROP 3 LASTPIN (1300 2975) SIG_NAME P3E_CPU0_PE1_PCH_CON_RXP<15>
J 0
(1310 2985);
DISPLAY 0.659574 (1310 2985);
PAINT MONO (1310 2985);
DISPLAY INVISIBLE (1310 2985);
FORCEPROP 1 LASTPIN (1300 2975) BN 15
J 0
(1288 2983);
DISPLAY 0.617021 (1288 2983);
PAINT PINK (1288 2983);
FORCEPROP 1 LAST PATH I295
J 0
(1348 2975);
DISPLAY 0.872340 (1348 2975);
PAINT GREEN (1348 2975);
DISPLAY INVISIBLE (1348 2975);
FORCEPROP 2 LAST CDS_LIB mstr_standard
J 0
(1350 2975);
PAINT MONO (1350 2975);
DISPLAY INVISIBLE (1350 2975);
FORCEPROP 1 LAST HDL_TAP TRUE
J 0
(1675 2850);
DISPLAY 0.638298 (1675 2850);
PAINT GREEN (1675 2850);
DISPLAY INVISIBLE (1675 2850);
FORCEPROP 1 LAST BODY_TYPE PLUMBING
J 0
(1350 3025);
DISPLAY 0.638298 (1350 3025);
PAINT GREEN (1350 3025);
DISPLAY INVISIBLE (1350 3025);
FORCEADD TAP..1
(1500 3025);
FORCEPROP 3 LASTPIN (1450 3025) SIG_NAME P3E_CPU0_PE1_PCH_CON_RXN<15>
J 0
(1460 3035);
DISPLAY 0.659574 (1460 3035);
PAINT MONO (1460 3035);
DISPLAY INVISIBLE (1460 3035);
FORCEPROP 1 LASTPIN (1450 3025) BN 15
J 0
(1438 3033);
DISPLAY 0.617021 (1438 3033);
PAINT PINK (1438 3033);
FORCEPROP 2 LAST CDS_LIB mstr_standard
J 0
(1500 3025);
PAINT MONO (1500 3025);
DISPLAY INVISIBLE (1500 3025);
FORCEPROP 1 LAST BODY_TYPE PLUMBING
J 0
(1500 3075);
DISPLAY 0.638298 (1500 3075);
PAINT GREEN (1500 3075);
DISPLAY INVISIBLE (1500 3075);
FORCEPROP 1 LAST PATH I296
J 0
(1498 3025);
DISPLAY 0.872340 (1498 3025);
PAINT GREEN (1498 3025);
DISPLAY INVISIBLE (1498 3025);
FORCEPROP 1 LAST HDL_TAP TRUE
J 0
(1825 2900);
DISPLAY 0.638298 (1825 2900);
PAINT GREEN (1825 2900);
DISPLAY INVISIBLE (1825 2900);
FORCEADD TAP..1
(1500 2875);
FORCEPROP 3 LASTPIN (1450 2875) SIG_NAME P3E_CPU0_PE1_PCH_CON_RXN<14>
J 0
(1460 2885);
DISPLAY 0.659574 (1460 2885);
PAINT MONO (1460 2885);
DISPLAY INVISIBLE (1460 2885);
FORCEPROP 1 LASTPIN (1450 2875) BN 14
J 0
(1438 2883);
DISPLAY 0.617021 (1438 2883);
PAINT GREEN (1438 2883);
FORCEPROP 1 LAST HDL_TAP TRUE
J 0
(1825 2750);
DISPLAY 0.638298 (1825 2750);
PAINT GREEN (1825 2750);
DISPLAY INVISIBLE (1825 2750);
FORCEPROP 1 LAST PATH I297
J 0
(1498 2875);
DISPLAY 0.872340 (1498 2875);
PAINT GREEN (1498 2875);
DISPLAY INVISIBLE (1498 2875);
FORCEPROP 1 LAST BODY_TYPE PLUMBING
J 0
(1500 2925);
DISPLAY 0.638298 (1500 2925);
PAINT GREEN (1500 2925);
DISPLAY INVISIBLE (1500 2925);
FORCEPROP 2 LAST CDS_LIB mstr_standard
J 0
(1500 2875);
PAINT MONO (1500 2875);
DISPLAY INVISIBLE (1500 2875);
FORCEADD TAP..1
(1350 2825);
FORCEPROP 3 LASTPIN (1300 2825) SIG_NAME P3E_CPU0_PE1_PCH_CON_RXP<14>
J 0
(1310 2835);
DISPLAY 0.659574 (1310 2835);
PAINT MONO (1310 2835);
DISPLAY INVISIBLE (1310 2835);
FORCEPROP 1 LASTPIN (1300 2825) BN 14
J 0
(1288 2833);
DISPLAY 0.617021 (1288 2833);
PAINT GREEN (1288 2833);
FORCEPROP 2 LAST CDS_LIB mstr_standard
J 0
(1350 2825);
PAINT MONO (1350 2825);
DISPLAY INVISIBLE (1350 2825);
FORCEPROP 1 LAST PATH I298
J 0
(1348 2825);
DISPLAY 0.872340 (1348 2825);
PAINT GREEN (1348 2825);
DISPLAY INVISIBLE (1348 2825);
FORCEPROP 1 LAST BODY_TYPE PLUMBING
J 0
(1350 2875);
DISPLAY 0.638298 (1350 2875);
PAINT GREEN (1350 2875);
DISPLAY INVISIBLE (1350 2875);
FORCEPROP 1 LAST HDL_TAP TRUE
J 0
(1675 2700);
DISPLAY 0.638298 (1675 2700);
PAINT GREEN (1675 2700);
DISPLAY INVISIBLE (1675 2700);
FORCEADD TAP..1
(1500 2625);
FORCEPROP 3 LASTPIN (1450 2625) SIG_NAME P3E_CPU0_PE1_PCH_CON_RXN<13>
J 0
(1460 2635);
DISPLAY 0.659574 (1460 2635);
PAINT MONO (1460 2635);
DISPLAY INVISIBLE (1460 2635);
FORCEPROP 1 LASTPIN (1450 2625) BN 13
J 0
(1438 2633);
DISPLAY 0.617021 (1438 2633);
PAINT GREEN (1438 2633);
FORCEPROP 2 LAST CDS_LIB mstr_standard
J 0
(1500 2625);
PAINT MONO (1500 2625);
DISPLAY INVISIBLE (1500 2625);
FORCEPROP 1 LAST BODY_TYPE PLUMBING
J 0
(1500 2675);
DISPLAY 0.638298 (1500 2675);
PAINT GREEN (1500 2675);
DISPLAY INVISIBLE (1500 2675);
FORCEPROP 1 LAST PATH I299
J 0
(1498 2625);
DISPLAY 0.872340 (1498 2625);
PAINT GREEN (1498 2625);
DISPLAY INVISIBLE (1498 2625);
FORCEPROP 1 LAST HDL_TAP TRUE
J 0
(1825 2500);
DISPLAY 0.638298 (1825 2500);
PAINT GREEN (1825 2500);
DISPLAY INVISIBLE (1825 2500);
FORCEADD TAP..1
(1350 2575);
FORCEPROP 3 LASTPIN (1300 2575) SIG_NAME P3E_CPU0_PE1_PCH_CON_RXP<13>
J 0
(1310 2585);
DISPLAY 0.659574 (1310 2585);
PAINT MONO (1310 2585);
DISPLAY INVISIBLE (1310 2585);
FORCEPROP 1 LASTPIN (1300 2575) BN 13
J 0
(1288 2583);
DISPLAY 0.617021 (1288 2583);
PAINT GREEN (1288 2583);
FORCEPROP 2 LAST CDS_LIB mstr_standard
J 0
(1350 2575);
PAINT MONO (1350 2575);
DISPLAY INVISIBLE (1350 2575);
FORCEPROP 1 LAST BODY_TYPE PLUMBING
J 0
(1350 2625);
DISPLAY 0.638298 (1350 2625);
PAINT GREEN (1350 2625);
DISPLAY INVISIBLE (1350 2625);
FORCEPROP 1 LAST PATH I300
J 0
(1348 2575);
DISPLAY 0.872340 (1348 2575);
PAINT GREEN (1348 2575);
DISPLAY INVISIBLE (1348 2575);
FORCEPROP 1 LAST HDL_TAP TRUE
J 0
(1675 2450);
DISPLAY 0.638298 (1675 2450);
PAINT GREEN (1675 2450);
DISPLAY INVISIBLE (1675 2450);
FORCEADD TAP..1
(1500 2475);
FORCEPROP 3 LASTPIN (1450 2475) SIG_NAME P3E_CPU0_PE1_PCH_CON_RXN<12>
J 0
(1460 2485);
DISPLAY 0.659574 (1460 2485);
PAINT MONO (1460 2485);
DISPLAY INVISIBLE (1460 2485);
FORCEPROP 1 LASTPIN (1450 2475) BN 12
J 0
(1438 2483);
DISPLAY 0.617021 (1438 2483);
PAINT GREEN (1438 2483);
FORCEPROP 1 LAST PATH I301
J 0
(1498 2475);
DISPLAY 0.872340 (1498 2475);
PAINT GREEN (1498 2475);
DISPLAY INVISIBLE (1498 2475);
FORCEPROP 1 LAST BODY_TYPE PLUMBING
J 0
(1500 2525);
DISPLAY 0.638298 (1500 2525);
PAINT GREEN (1500 2525);
DISPLAY INVISIBLE (1500 2525);
FORCEPROP 2 LAST CDS_LIB mstr_standard
J 0
(1500 2475);
PAINT MONO (1500 2475);
DISPLAY INVISIBLE (1500 2475);
FORCEPROP 1 LAST HDL_TAP TRUE
J 0
(1825 2350);
DISPLAY 0.638298 (1825 2350);
PAINT GREEN (1825 2350);
DISPLAY INVISIBLE (1825 2350);
FORCEADD TAP..1
(1350 2425);
FORCEPROP 3 LASTPIN (1300 2425) SIG_NAME P3E_CPU0_PE1_PCH_CON_RXP<12>
J 0
(1310 2435);
DISPLAY 0.659574 (1310 2435);
PAINT MONO (1310 2435);
DISPLAY INVISIBLE (1310 2435);
FORCEPROP 1 LASTPIN (1300 2425) BN 12
J 0
(1288 2433);
DISPLAY 0.617021 (1288 2433);
PAINT GREEN (1288 2433);
FORCEPROP 1 LAST HDL_TAP TRUE
J 0
(1675 2300);
DISPLAY 0.638298 (1675 2300);
PAINT GREEN (1675 2300);
DISPLAY INVISIBLE (1675 2300);
FORCEPROP 2 LAST CDS_LIB mstr_standard
J 0
(1350 2425);
PAINT MONO (1350 2425);
DISPLAY INVISIBLE (1350 2425);
FORCEPROP 1 LAST BODY_TYPE PLUMBING
J 0
(1350 2475);
DISPLAY 0.638298 (1350 2475);
PAINT GREEN (1350 2475);
DISPLAY INVISIBLE (1350 2475);
FORCEPROP 1 LAST PATH I302
J 0
(1348 2425);
DISPLAY 0.872340 (1348 2425);
PAINT GREEN (1348 2425);
DISPLAY INVISIBLE (1348 2425);
FORCEADD TAP..1
(1500 2325);
FORCEPROP 3 LASTPIN (1450 2325) SIG_NAME P3E_CPU0_PE1_PCH_CON_RXN<11>
J 0
(1460 2335);
DISPLAY 0.659574 (1460 2335);
PAINT MONO (1460 2335);
DISPLAY INVISIBLE (1460 2335);
FORCEPROP 1 LASTPIN (1450 2325) BN 11
J 0
(1438 2333);
DISPLAY 0.617021 (1438 2333);
PAINT GREEN (1438 2333);
FORCEPROP 1 LAST PATH I303
J 0
(1498 2325);
DISPLAY 0.872340 (1498 2325);
PAINT GREEN (1498 2325);
DISPLAY INVISIBLE (1498 2325);
FORCEPROP 2 LAST CDS_LIB mstr_standard
J 0
(1500 2325);
PAINT MONO (1500 2325);
DISPLAY INVISIBLE (1500 2325);
FORCEPROP 1 LAST BODY_TYPE PLUMBING
J 0
(1500 2375);
DISPLAY 0.638298 (1500 2375);
PAINT GREEN (1500 2375);
DISPLAY INVISIBLE (1500 2375);
FORCEPROP 1 LAST HDL_TAP TRUE
J 0
(1825 2200);
DISPLAY 0.638298 (1825 2200);
PAINT GREEN (1825 2200);
DISPLAY INVISIBLE (1825 2200);
FORCEADD TAP..1
(1350 2275);
FORCEPROP 3 LASTPIN (1300 2275) SIG_NAME P3E_CPU0_PE1_PCH_CON_RXP<11>
J 0
(1310 2285);
DISPLAY 0.659574 (1310 2285);
PAINT MONO (1310 2285);
DISPLAY INVISIBLE (1310 2285);
FORCEPROP 1 LASTPIN (1300 2275) BN 11
J 0
(1288 2283);
DISPLAY 0.617021 (1288 2283);
PAINT GREEN (1288 2283);
FORCEPROP 1 LAST PATH I304
J 0
(1348 2275);
DISPLAY 0.872340 (1348 2275);
PAINT GREEN (1348 2275);
DISPLAY INVISIBLE (1348 2275);
FORCEPROP 1 LAST BODY_TYPE PLUMBING
J 0
(1350 2325);
DISPLAY 0.638298 (1350 2325);
PAINT GREEN (1350 2325);
DISPLAY INVISIBLE (1350 2325);
FORCEPROP 2 LAST CDS_LIB mstr_standard
J 0
(1350 2275);
PAINT MONO (1350 2275);
DISPLAY INVISIBLE (1350 2275);
FORCEPROP 1 LAST HDL_TAP TRUE
J 0
(1675 2150);
DISPLAY 0.638298 (1675 2150);
PAINT GREEN (1675 2150);
DISPLAY INVISIBLE (1675 2150);
FORCEADD TAP..1
(1500 2175);
FORCEPROP 3 LASTPIN (1450 2175) SIG_NAME P3E_CPU0_PE1_PCH_CON_RXN<10>
J 0
(1460 2185);
DISPLAY 0.659574 (1460 2185);
PAINT MONO (1460 2185);
DISPLAY INVISIBLE (1460 2185);
FORCEPROP 1 LASTPIN (1450 2175) BN 10
J 0
(1438 2183);
DISPLAY 0.617021 (1438 2183);
PAINT GREEN (1438 2183);
FORCEPROP 2 LAST CDS_LIB mstr_standard
J 0
(1500 2175);
PAINT MONO (1500 2175);
DISPLAY INVISIBLE (1500 2175);
FORCEPROP 1 LAST BODY_TYPE PLUMBING
J 0
(1500 2225);
DISPLAY 0.638298 (1500 2225);
PAINT GREEN (1500 2225);
DISPLAY INVISIBLE (1500 2225);
FORCEPROP 1 LAST PATH I305
J 0
(1498 2175);
DISPLAY 0.872340 (1498 2175);
PAINT GREEN (1498 2175);
DISPLAY INVISIBLE (1498 2175);
FORCEPROP 1 LAST HDL_TAP TRUE
J 0
(1825 2050);
DISPLAY 0.638298 (1825 2050);
PAINT GREEN (1825 2050);
DISPLAY INVISIBLE (1825 2050);
FORCEADD TAP..1
(1350 2125);
FORCEPROP 3 LASTPIN (1300 2125) SIG_NAME P3E_CPU0_PE1_PCH_CON_RXP<10>
J 0
(1310 2135);
DISPLAY 0.659574 (1310 2135);
PAINT MONO (1310 2135);
DISPLAY INVISIBLE (1310 2135);
FORCEPROP 1 LASTPIN (1300 2125) BN 10
J 0
(1288 2133);
DISPLAY 0.617021 (1288 2133);
PAINT GREEN (1288 2133);
FORCEPROP 2 LAST CDS_LIB mstr_standard
J 0
(1350 2125);
PAINT MONO (1350 2125);
DISPLAY INVISIBLE (1350 2125);
FORCEPROP 1 LAST PATH I306
J 0
(1348 2125);
DISPLAY 0.872340 (1348 2125);
PAINT GREEN (1348 2125);
DISPLAY INVISIBLE (1348 2125);
FORCEPROP 1 LAST BODY_TYPE PLUMBING
J 0
(1350 2175);
DISPLAY 0.638298 (1350 2175);
PAINT GREEN (1350 2175);
DISPLAY INVISIBLE (1350 2175);
FORCEPROP 1 LAST HDL_TAP TRUE
J 0
(1675 2000);
DISPLAY 0.638298 (1675 2000);
PAINT GREEN (1675 2000);
DISPLAY INVISIBLE (1675 2000);
FORCEADD OFFPAGE..2
(2850 3925);
FORCEPROP 2 LAST $XR2 147 
J 0
(3279 3925);
DISPLAY 0.638298 (3279 3925);
PAINT MONO (3279 3925);
FORCEPROP 2 LAST $XR1 119 
J 0
(3159 3925);
DISPLAY 0.638298 (3159 3925);
PAINT MONO (3159 3925);
FORCEPROP 2 LAST $XR0 133 
J 0
(3039 3925);
DISPLAY 0.638298 (3039 3925);
PAINT MONO (3039 3925);
FORCEPROP 1 LAST COMMENT_BODY TRUE
J 0
(2805 3830);
DISPLAY 0.872340 (2805 3830);
PAINT GREEN (2805 3830);
DISPLAY INVISIBLE (2805 3830);
FORCEPROP 2 LAST CDS_LIB mstr_standard
J 0
(2850 3925);
PAINT MONO (2850 3925);
DISPLAY INVISIBLE (2850 3925);
FORCEPROP 2 LAST PATH I310
J 0
(3025 4000);
DISPLAY 1.021277 (3025 4000);
PAINT ORANGE (3025 4000);
DISPLAY INVISIBLE (3025 4000);
FORCEPROP 1 LAST OFFPAGE TRUE
J 0
(3175 3800);
DISPLAY 0.872340 (3175 3800);
PAINT GREEN (3175 3800);
DISPLAY INVISIBLE (3175 3800);
FORCEADD OFFPAGE..2
(2325 3675);
FORCEPROP 2 LAST $XR0 142 
J 0
(2514 3675);
DISPLAY 0.638298 (2514 3675);
PAINT MONO (2514 3675);
FORCEPROP 1 LAST COMMENT_BODY TRUE
J 0
(2280 3580);
DISPLAY 0.872340 (2280 3580);
PAINT GREEN (2280 3580);
DISPLAY INVISIBLE (2280 3580);
FORCEPROP 2 LAST CDS_LIB mstr_standard
J 0
(2325 3675);
PAINT MONO (2325 3675);
DISPLAY INVISIBLE (2325 3675);
FORCEPROP 2 LAST PATH I314
J 0
(2500 3750);
DISPLAY 1.021277 (2500 3750);
PAINT ORANGE (2500 3750);
DISPLAY INVISIBLE (2500 3750);
FORCEPROP 1 LAST OFFPAGE TRUE
J 0
(2650 3550);
DISPLAY 0.872340 (2650 3550);
PAINT GREEN (2650 3550);
DISPLAY INVISIBLE (2650 3550);
FORCEADD CAP_A..1
(-1950 1350);
FORCEPROP 1 LASTPIN (-1950 1250) $PN 2
J 0
(-1940 1230);
DISPLAY 0.617021 (-1940 1230);
PAINT ORANGE (-1940 1230);
FORCEPROP 1 LAST MATERIAL X7R
J 0
(-1900 1250);
DISPLAY 0.617021 (-1900 1250);
PAINT SKYBLUE (-1900 1250);
FORCEPROP 1 LAST TOLERANCE 10%
J 0
(-1900 1300);
DISPLAY 0.617021 (-1900 1300);
PAINT SKYBLUE (-1900 1300);
FORCEPROP 1 LASTPIN (-1950 1450) $PN 1
J 0
(-1940 1430);
DISPLAY 0.617021 (-1940 1430);
PAINT ORANGE (-1940 1430);
FORCEPROP 1 LAST VOLTAGE 16V
J 0
(-1900 1350);
DISPLAY 0.617021 (-1900 1350);
PAINT SKYBLUE (-1900 1350);
FORCEPROP 1 LAST PART_NUMBER A36096-030
J 0
(-1900 1200);
DISPLAY 0.617021 (-1900 1200);
PAINT BLUE (-1900 1200);
FORCEPROP 1 LAST VALUE 0.1UF
J 0
(-1900 1400);
DISPLAY 0.617021 (-1900 1400);
PAINT SKYBLUE (-1900 1400);
FORCEPROP 1 LAST PACK_TYPE 0402V
J 0
(-1900 1150);
DISPLAY 0.617021 (-1900 1150);
PAINT SKYBLUE (-1900 1150);
FORCEPROP 1 LAST LOCATION C2U23
J 0
(-1900 1450);
DISPLAY 0.617021 (-1900 1450);
PAINT AQUA (-1900 1450);
FORCEPROP 2 LAST CDS_LIB dev_discrete
J 0
(-1950 1350);
PAINT ORANGE (-1950 1350);
DISPLAY INVISIBLE (-1950 1350);
FORCEPROP 2 LAST CDS_LOCATION C2U23
J 0
(-1900 1450);
DISPLAY 0.617021 (-1900 1450);
PAINT AQUA (-1900 1450);
DISPLAY INVISIBLE (-1900 1450);
FORCEPROP 2 LAST CDS_SEC 1
J 0
(-1900 1500);
PAINT ORANGE (-1900 1500);
DISPLAY INVISIBLE (-1900 1500);
FORCEPROP 1 LAST PATH I315
J 0
(-1900 1500);
DISPLAY 0.978723 (-1900 1500);
PAINT WHITE (-1900 1500);
DISPLAY INVISIBLE (-1900 1500);
FORCEPROP 2 LAST SEC 1
J 0
(-1900 1550);
PAINT MONO (-1900 1550);
DISPLAY INVISIBLE (-1900 1550);
FORCEPROP 2 LAST SEC_TYPE 0402V
J 0
(-1900 1550);
DISPLAY 1.021277 (-1900 1550);
PAINT ORANGE (-1900 1550);
DISPLAY INVISIBLE (-1900 1550);
FORCEPROP 0 LAST ROOM IO_SLOT
J 0
(-1900 1550);
DISPLAY 1.021277 (-1900 1550);
PAINT ORANGE (-1900 1550);
DISPLAY INVISIBLE (-1900 1550);
FORCEADD GND..1
(-1950 950);
FORCEPROP 3 LASTPIN (-1950 1000) SIG_NAME GND\g
J 0
(-1940 1010);
DISPLAY 0.659574 (-1940 1010);
PAINT MONO (-1940 1010);
DISPLAY INVISIBLE (-1940 1010);
FORCEPROP 1 LAST PATH I316
J 0
(-1875 950);
DISPLAY 0.872340 (-1875 950);
PAINT AQUA (-1875 950);
DISPLAY INVISIBLE (-1875 950);
FORCEPROP 1 LAST BODY_TYPE PLUMBING
J 0
(-1995 907);
DISPLAY 0.340426 (-1995 907);
PAINT GREEN (-1995 907);
DISPLAY INVISIBLE (-1995 907);
FORCEPROP 2 LAST CDS_LIB mstr_symbols
J 0
(-1950 950);
PAINT MONO (-1950 950);
DISPLAY INVISIBLE (-1950 950);
FORCEPROP 1 LAST SIZE 1B
J 0
(-1875 900);
DISPLAY 0.872340 (-1875 900);
PAINT AQUA (-1875 900);
DISPLAY INVISIBLE (-1875 900);
FORCEPROP 1 LAST VOLTAGE 0
J 0
(-1950 950);
PAINT SKYBLUE (-1950 950);
DISPLAY INVISIBLE (-1950 950);
FORCEPROP 1 LAST HDL_POWER GND
J 0
(-1950 1100);
DISPLAY 0.872340 (-1950 1100);
PAINT GREEN (-1950 1100);
DISPLAY INVISIBLE (-1950 1100);
FORCEADD CAP_A..1
(-2350 1375);
FORCEPROP 1 LASTPIN (-2350 1275) $PN 2
J 0
(-2340 1255);
DISPLAY 0.617021 (-2340 1255);
PAINT ORANGE (-2340 1255);
FORCEPROP 1 LASTPIN (-2350 1475) $PN 1
J 0
(-2340 1455);
DISPLAY 0.617021 (-2340 1455);
PAINT ORANGE (-2340 1455);
FORCEPROP 1 LAST LOCATION C2U22
J 0
(-2300 1475);
DISPLAY 0.617021 (-2300 1475);
PAINT AQUA (-2300 1475);
FORCEPROP 1 LAST VALUE 0.1UF
J 0
(-2300 1425);
DISPLAY 0.617021 (-2300 1425);
PAINT SKYBLUE (-2300 1425);
FORCEPROP 1 LAST MATERIAL X7R
J 0
(-2300 1275);
DISPLAY 0.617021 (-2300 1275);
PAINT SKYBLUE (-2300 1275);
FORCEPROP 1 LAST TOLERANCE 10%
J 0
(-2300 1325);
DISPLAY 0.617021 (-2300 1325);
PAINT SKYBLUE (-2300 1325);
FORCEPROP 1 LAST VOLTAGE 16V
J 0
(-2300 1375);
DISPLAY 0.617021 (-2300 1375);
PAINT SKYBLUE (-2300 1375);
FORCEPROP 1 LAST PACK_TYPE 0402V
J 0
(-2300 1175);
DISPLAY 0.617021 (-2300 1175);
PAINT SKYBLUE (-2300 1175);
FORCEPROP 1 LAST PART_NUMBER A36096-030
J 0
(-2300 1225);
DISPLAY 0.617021 (-2300 1225);
PAINT BLUE (-2300 1225);
FORCEPROP 2 LAST CDS_LIB dev_discrete
J 0
(-2350 1375);
PAINT ORANGE (-2350 1375);
DISPLAY INVISIBLE (-2350 1375);
FORCEPROP 2 LAST CDS_LOCATION C2U22
J 0
(-2300 1475);
DISPLAY 0.617021 (-2300 1475);
PAINT AQUA (-2300 1475);
DISPLAY INVISIBLE (-2300 1475);
FORCEPROP 2 LAST CDS_SEC 1
J 0
(-2300 1525);
PAINT ORANGE (-2300 1525);
DISPLAY INVISIBLE (-2300 1525);
FORCEPROP 1 LAST PATH I318
J 0
(-2300 1525);
DISPLAY 0.978723 (-2300 1525);
PAINT WHITE (-2300 1525);
DISPLAY INVISIBLE (-2300 1525);
FORCEPROP 0 LAST ROOM IO_SLOT
J 0
(-2300 1575);
DISPLAY 1.021277 (-2300 1575);
PAINT ORANGE (-2300 1575);
DISPLAY INVISIBLE (-2300 1575);
FORCEPROP 2 LAST SEC_TYPE 0402V
J 0
(-2300 1575);
DISPLAY 1.021277 (-2300 1575);
PAINT ORANGE (-2300 1575);
DISPLAY INVISIBLE (-2300 1575);
FORCEPROP 2 LAST SEC 1
J 0
(-2300 1575);
PAINT MONO (-2300 1575);
DISPLAY INVISIBLE (-2300 1575);
FORCEADD P3V3_STBY..1
(-2350 1625);
FORCEPROP 3 LASTPIN (-2350 1575) SIG_NAME P3V3_STBY\g
J 0
(-2340 1585);
DISPLAY 0.659574 (-2340 1585);
PAINT MONO (-2340 1585);
DISPLAY INVISIBLE (-2340 1585);
FORCEPROP 1 LAST HDL_POWER P3V3_STBY
J 0
(-2650 1500);
DISPLAY 0.872340 (-2650 1500);
PAINT ORANGE (-2650 1500);
DISPLAY INVISIBLE (-2650 1500);
FORCEPROP 1 LAST VOLTAGE 3.3V
J 0
(-2395 1582);
DISPLAY 0.340426 (-2395 1582);
PAINT SKYBLUE (-2395 1582);
DISPLAY INVISIBLE (-2395 1582);
FORCEPROP 1 LAST BODY_TYPE PLUMBING
J 0
(-2395 1582);
DISPLAY 0.340426 (-2395 1582);
PAINT GREEN (-2395 1582);
DISPLAY INVISIBLE (-2395 1582);
FORCEPROP 1 LAST SIZE 1B
J 0
(-2305 1647);
DISPLAY 0.340426 (-2305 1647);
PAINT GREEN (-2305 1647);
DISPLAY INVISIBLE (-2305 1647);
FORCEPROP 1 LAST PATH I319
J 0
(-2305 1627);
DISPLAY 0.340426 (-2305 1627);
PAINT GREEN (-2305 1627);
DISPLAY INVISIBLE (-2305 1627);
FORCEPROP 2 LAST CDS_LIB mstr_symbols
J 0
(-2350 1625);
PAINT MONO (-2350 1625);
DISPLAY INVISIBLE (-2350 1625);
FORCEADD OFFPAGE..6
(-3175 4500);
FORCEPROP 2 LAST $XR0 160 
J 0
(-3545 4500);
DISPLAY 0.638298 (-3545 4500);
PAINT MONO (-3545 4500);
FORCEPROP 2 LAST PATH I323
J 0
(-3125 4575);
DISPLAY 1.021277 (-3125 4575);
PAINT ORANGE (-3125 4575);
DISPLAY INVISIBLE (-3125 4575);
FORCEPROP 1 LAST OFFPAGE TRUE
J 0
(-2850 4375);
DISPLAY 0.872340 (-2850 4375);
PAINT GREEN (-2850 4375);
DISPLAY INVISIBLE (-2850 4375);
FORCEPROP 2 LAST CDS_LIB mstr_standard
J 0
(-3175 4500);
PAINT MONO (-3175 4500);
DISPLAY INVISIBLE (-3175 4500);
FORCEPROP 1 LAST COMMENT_BODY TRUE
J 0
(-3075 4425);
DISPLAY 0.872340 (-3075 4425);
PAINT GREEN (-3075 4425);
DISPLAY INVISIBLE (-3075 4425);
FORCEADD OFFPAGE..3
(-875 4500);
FORCEPROP 2 LAST $XR0 108 
J 0
(-661 4500);
DISPLAY 0.638298 (-661 4500);
PAINT MONO (-661 4500);
FORCEPROP 1 LAST OFFPAGE TRUE
J 0
(-550 4375);
DISPLAY 0.872340 (-550 4375);
PAINT GREEN (-550 4375);
DISPLAY INVISIBLE (-550 4375);
FORCEPROP 2 LAST PATH I324
J 0
(-825 4575);
DISPLAY 1.021277 (-825 4575);
PAINT ORANGE (-825 4575);
DISPLAY INVISIBLE (-825 4575);
FORCEPROP 1 LAST COMMENT_BODY TRUE
J 0
(-925 4400);
DISPLAY 0.872340 (-925 4400);
PAINT GREEN (-925 4400);
DISPLAY INVISIBLE (-925 4400);
FORCEPROP 2 LAST CDS_LIB mstr_standard
J 0
(-875 4500);
PAINT MONO (-875 4500);
DISPLAY INVISIBLE (-875 4500);
FORCEADD OFFPAGE..2
(-875 4250);
FORCEPROP 2 LAST $XR0 108 
J 0
(-686 4250);
DISPLAY 0.638298 (-686 4250);
PAINT MONO (-686 4250);
FORCEPROP 1 LAST OFFPAGE TRUE
J 0
(-550 4125);
DISPLAY 0.872340 (-550 4125);
PAINT GREEN (-550 4125);
DISPLAY INVISIBLE (-550 4125);
FORCEPROP 2 LAST PATH I325
J 0
(-675 4325);
DISPLAY 1.021277 (-675 4325);
PAINT ORANGE (-675 4325);
DISPLAY INVISIBLE (-675 4325);
FORCEPROP 2 LAST CDS_LIB mstr_standard
J 0
(-875 4250);
PAINT MONO (-875 4250);
DISPLAY INVISIBLE (-875 4250);
FORCEPROP 1 LAST COMMENT_BODY TRUE
J 0
(-920 4155);
DISPLAY 0.872340 (-920 4155);
PAINT GREEN (-920 4155);
DISPLAY INVISIBLE (-920 4155);
FORCEADD OFFPAGE..1
(-3175 4250);
FORCEPROP 2 LAST $XR0 160 
J 0
(-3547 4250);
DISPLAY 0.638298 (-3547 4250);
PAINT MONO (-3547 4250);
FORCEPROP 2 LAST PATH I329
J 0
(-3125 4325);
DISPLAY 1.021277 (-3125 4325);
PAINT ORANGE (-3125 4325);
DISPLAY INVISIBLE (-3125 4325);
FORCEPROP 1 LAST OFFPAGE TRUE
J 0
(-2850 4125);
DISPLAY 0.872340 (-2850 4125);
PAINT GREEN (-2850 4125);
DISPLAY INVISIBLE (-2850 4125);
FORCEPROP 1 LAST COMMENT_BODY TRUE
J 0
(-3050 4150);
DISPLAY 0.872340 (-3050 4150);
PAINT GREEN (-3050 4150);
DISPLAY INVISIBLE (-3050 4150);
FORCEPROP 2 LAST CDS_LIB mstr_standard
J 0
(-3175 4250);
PAINT MONO (-3175 4250);
DISPLAY INVISIBLE (-3175 4250);
FORCEADD RES..1
(-2275 4500);
FORCEPROP 1 LAST VALUE 20.0
J 2
(-2375 4450);
DISPLAY 0.617021 (-2375 4450);
PAINT SKYBLUE (-2375 4450);
FORCEPROP 1 LASTPIN (-2375 4500) $PN 1
J 0
(-2363 4512);
DISPLAY 0.617021 (-2363 4512);
PAINT ORANGE (-2363 4512);
FORCEPROP 1 LAST LOCATION R2U31
J 0
(-2625 4450);
DISPLAY 0.617021 (-2625 4450);
PAINT AQUA (-2625 4450);
FORCEPROP 1 LASTPIN (-2175 4500) $PN 2
J 0
(-2213 4512);
DISPLAY 0.617021 (-2213 4512);
PAINT ORANGE (-2213 4512);
FORCEPROP 1 LAST TOLERANCE 1%
J 0
(-2200 4450);
DISPLAY 0.617021 (-2200 4450);
PAINT SKYBLUE (-2200 4450);
FORCEPROP 1 LAST MATERIAL CHIP
J 0
(-2125 4450);
DISPLAY 0.617021 (-2125 4450);
PAINT SKYBLUE (-2125 4450);
FORCEPROP 1 LAST PART_NUMBER G21796-173
J 0
(-1975 4450);
DISPLAY 0.617021 (-1975 4450);
PAINT BLUE (-1975 4450);
FORCEPROP 1 LAST WATTAGE 1/16W
J 2
(-1625 4450);
DISPLAY 0.617021 (-1625 4450);
PAINT SKYBLUE (-1625 4450);
FORCEPROP 1 LAST PACK_TYPE 0402
J 0
(-1575 4450);
DISPLAY 0.617021 (-1575 4450);
PAINT SKYBLUE (-1575 4450);
FORCEPROP 0 LAST BOM_COST SM_CONTROLLER
J 0
(-2025 4650);
DISPLAY 1.021277 (-2025 4650);
PAINT ORANGE (-2025 4650);
DISPLAY INVISIBLE (-2025 4650);
FORCEPROP 2 LAST CDS_SEC 1
J 0
(-2325 4700);
PAINT MONO (-2325 4700);
DISPLAY INVISIBLE (-2325 4700);
FORCEPROP 2 LAST $SEC 1
J 0
(-2325 4700);
PAINT MONO (-2325 4700);
DISPLAY INVISIBLE (-2325 4700);
FORCEPROP 1 LAST PATH I330
J 0
(-2325 4650);
DISPLAY 0.978723 (-2325 4650);
PAINT WHITE (-2325 4650);
DISPLAY INVISIBLE (-2325 4650);
FORCEPROP 0 LAST ROOM SMBUS
J 0
(-2025 4550);
DISPLAY 1.021277 (-2025 4550);
PAINT ORANGE (-2025 4550);
DISPLAY INVISIBLE (-2025 4550);
FORCEPROP 0 LAST SKU B
J 0
(-2025 4550);
DISPLAY 1.021277 (-2025 4550);
PAINT ORANGE (-2025 4550);
DISPLAY INVISIBLE (-2025 4550);
FORCEPROP 2 LAST CDS_LIB mstr_discrete
J 0
(-2275 4500);
PAINT MONO (-2275 4500);
DISPLAY INVISIBLE (-2275 4500);
FORCEPROP 2 LAST CDS_LOCATION R2U31
J 0
(-2525 4450);
DISPLAY 0.617021 (-2525 4450);
PAINT AQUA (-2525 4450);
DISPLAY INVISIBLE (-2525 4450);
FORCEADD OFFPAGE..2
(2850 3875);
FORCEPROP 2 LAST $XR0 119 
J 0
(3039 3875);
DISPLAY 0.638298 (3039 3875);
PAINT MONO (3039 3875);
FORCEPROP 1 LAST COMMENT_BODY TRUE
J 0
(2805 3780);
DISPLAY 0.872340 (2805 3780);
PAINT GREEN (2805 3780);
DISPLAY INVISIBLE (2805 3780);
FORCEPROP 2 LAST CDS_LIB mstr_standard
J 0
(2850 3875);
PAINT MONO (2850 3875);
DISPLAY INVISIBLE (2850 3875);
FORCEPROP 2 LAST PATH I333
J 0
(3025 3950);
DISPLAY 1.021277 (3025 3950);
PAINT ORANGE (3025 3950);
DISPLAY INVISIBLE (3025 3950);
FORCEPROP 1 LAST OFFPAGE TRUE
J 0
(3175 3750);
DISPLAY 0.872340 (3175 3750);
PAINT GREEN (3175 3750);
DISPLAY INVISIBLE (3175 3750);
FORCEADD OFFPAGE..2
R 2
(-2000 3675);
FORCEPROP 2 LAST $XR1 119 
J 0
(-2405 3675);
DISPLAY 0.638298 (-2405 3675);
PAINT MONO (-2405 3675);
FORCEPROP 2 LAST $XR0 125 
J 0
(-2285 3675);
DISPLAY 0.638298 (-2285 3675);
PAINT MONO (-2285 3675);
FORCEPROP 2 LAST CDS_LIB mstr_standard
J 0
(-2000 3675);
PAINT MONO (-2000 3675);
DISPLAY INVISIBLE (-2000 3675);
FORCEPROP 2 LAST PATH I338
J 0
(-1950 3750);
DISPLAY 1.021277 (-1950 3750);
PAINT ORANGE (-1950 3750);
DISPLAY INVISIBLE (-1950 3750);
FORCEPROP 1 LAST OFFPAGE TRUE
J 2
(-2325 3550);
DISPLAY 0.872340 (-2325 3550);
PAINT GREEN (-2325 3550);
DISPLAY INVISIBLE (-2325 3550);
FORCEPROP 1 LAST COMMENT_BODY TRUE
J 2
(-1955 3580);
DISPLAY 0.872340 (-1955 3580);
PAINT GREEN (-1955 3580);
DISPLAY INVISIBLE (-1955 3580);
FORCEADD RES..1
(-2275 4250);
FORCEPROP 1 LAST VALUE 20.0
J 2
(-2375 4200);
DISPLAY 0.617021 (-2375 4200);
PAINT SKYBLUE (-2375 4200);
FORCEPROP 1 LASTPIN (-2375 4250) $PN 1
J 0
(-2363 4262);
DISPLAY 0.617021 (-2363 4262);
PAINT ORANGE (-2363 4262);
FORCEPROP 1 LASTPIN (-2175 4250) $PN 2
J 0
(-2213 4262);
DISPLAY 0.617021 (-2213 4262);
PAINT ORANGE (-2213 4262);
FORCEPROP 1 LAST LOCATION R2U32
J 0
(-2625 4200);
DISPLAY 0.617021 (-2625 4200);
PAINT AQUA (-2625 4200);
FORCEPROP 1 LAST TOLERANCE 1%
J 0
(-2200 4200);
DISPLAY 0.617021 (-2200 4200);
PAINT SKYBLUE (-2200 4200);
FORCEPROP 1 LAST PACK_TYPE 0402
J 0
(-1575 4200);
DISPLAY 0.617021 (-1575 4200);
PAINT SKYBLUE (-1575 4200);
FORCEPROP 1 LAST WATTAGE 1/16W
J 2
(-1625 4200);
DISPLAY 0.617021 (-1625 4200);
PAINT SKYBLUE (-1625 4200);
FORCEPROP 1 LAST MATERIAL CHIP
J 0
(-2125 4200);
DISPLAY 0.617021 (-2125 4200);
PAINT SKYBLUE (-2125 4200);
FORCEPROP 1 LAST PART_NUMBER G21796-173
J 0
(-1975 4200);
DISPLAY 0.617021 (-1975 4200);
PAINT BLUE (-1975 4200);
FORCEPROP 0 LAST BOM_COST SM_CONTROLLER
J 0
(-2025 4400);
DISPLAY 1.021277 (-2025 4400);
PAINT ORANGE (-2025 4400);
DISPLAY INVISIBLE (-2025 4400);
FORCEPROP 0 LAST ROOM SMBUS
J 0
(-2025 4300);
DISPLAY 1.021277 (-2025 4300);
PAINT ORANGE (-2025 4300);
DISPLAY INVISIBLE (-2025 4300);
FORCEPROP 0 LAST SKU B
J 0
(-2025 4300);
DISPLAY 1.021277 (-2025 4300);
PAINT ORANGE (-2025 4300);
DISPLAY INVISIBLE (-2025 4300);
FORCEPROP 2 LAST CDS_SEC 1
J 0
(-2325 4450);
PAINT MONO (-2325 4450);
DISPLAY INVISIBLE (-2325 4450);
FORCEPROP 2 LAST $SEC 1
J 0
(-2325 4450);
PAINT MONO (-2325 4450);
DISPLAY INVISIBLE (-2325 4450);
FORCEPROP 1 LAST PATH I339
J 0
(-2325 4400);
DISPLAY 0.978723 (-2325 4400);
PAINT WHITE (-2325 4400);
DISPLAY INVISIBLE (-2325 4400);
FORCEPROP 2 LAST CDS_LIB mstr_discrete
J 0
(-2275 4250);
PAINT MONO (-2275 4250);
DISPLAY INVISIBLE (-2275 4250);
FORCEPROP 2 LAST CDS_LOCATION R2U32
J 0
(-2525 4200);
DISPLAY 0.617021 (-2525 4200);
PAINT AQUA (-2525 4200);
DISPLAY INVISIBLE (-2525 4200);
FORCEADD RES..1
(2600 3775);
FORCEPROP 1 LASTPIN (2500 3775) $PN 1
J 0
(2512 3787);
DISPLAY 0.617021 (2512 3787);
PAINT ORANGE (2512 3787);
FORCEPROP 1 LASTPIN (2700 3775) $PN 2
J 0
(2662 3787);
DISPLAY 0.617021 (2662 3787);
PAINT ORANGE (2662 3787);
FORCEPROP 1 LAST LOCATION R7E22
J 0
(2550 3825);
DISPLAY 0.617021 (2550 3825);
PAINT AQUA (2550 3825);
FORCEPROP 1 LAST TOLERANCE 5%
J 0
(2600 3725);
DISPLAY 0.617021 (2600 3725);
PAINT SKYBLUE (2600 3725);
FORCEPROP 1 LAST PART_NUMBER G21497-005
J 0
(2950 3725);
DISPLAY 0.617021 (2950 3725);
PAINT BLUE (2950 3725);
FORCEPROP 1 LAST PACK_TYPE 0402
J 0
(2825 3725);
DISPLAY 0.617021 (2825 3725);
PAINT SKYBLUE (2825 3725);
FORCEPROP 1 LAST MATERIAL CHIP
J 0
(2700 3725);
DISPLAY 0.617021 (2700 3725);
PAINT SKYBLUE (2700 3725);
FORCEPROP 1 LAST VALUE 0.0
J 2
(2550 3725);
DISPLAY 0.617021 (2550 3725);
PAINT SKYBLUE (2550 3725);
FORCEPROP 1 LAST WATTAGE 1/16W
J 2
(2450 3725);
DISPLAY 0.617021 (2450 3725);
PAINT SKYBLUE (2450 3725);
FORCEPROP 2 LAST CDS_LIB mstr_discrete
J 0
(2600 3775);
PAINT ORANGE (2600 3775);
DISPLAY INVISIBLE (2600 3775);
FORCEPROP 0 LAST ROOM IO_SLOT
J 0
(2550 3975);
DISPLAY 1.021277 (2550 3975);
PAINT ORANGE (2550 3975);
DISPLAY INVISIBLE (2550 3975);
FORCEPROP 1 LAST PATH I341
J 0
(2550 3925);
DISPLAY 0.978723 (2550 3925);
PAINT WHITE (2550 3925);
DISPLAY INVISIBLE (2550 3925);
FORCEPROP 2 LAST SEC 1
J 0
(2550 3975);
DISPLAY 0.680851 (2550 3975);
PAINT MONO (2550 3975);
DISPLAY INVISIBLE (2550 3975);
FORCEPROP 2 LAST SEC_TYPE 0402
J 0
(2550 3975);
DISPLAY 1.021277 (2550 3975);
PAINT ORANGE (2550 3975);
DISPLAY INVISIBLE (2550 3975);
FORCEADD OFFPAGE..1
(1850 3775);
FORCEPROP 2 LAST PATH I342
J 0
(1900 3850);
DISPLAY 1.021277 (1900 3850);
PAINT ORANGE (1900 3850);
DISPLAY INVISIBLE (1900 3850);
FORCEPROP 1 LAST COMMENT_BODY TRUE
J 0
(1975 3675);
DISPLAY 0.872340 (1975 3675);
PAINT GREEN (1975 3675);
DISPLAY INVISIBLE (1975 3675);
FORCEPROP 2 LAST CDS_LIB mstr_standard
J 0
(1850 3775);
PAINT ORANGE (1850 3775);
DISPLAY INVISIBLE (1850 3775);
FORCEPROP 1 LAST OFFPAGE TRUE
J 0
(2175 3650);
DISPLAY 0.872340 (2175 3650);
PAINT GREEN (2175 3650);
DISPLAY INVISIBLE (2175 3650);
FORCEPROP 2 LAST $XR1 147 
J 0
(1424 3775);
DISPLAY 0.638298 (1424 3775);
PAINT MONO (1424 3775);
DISPLAY INVISIBLE (1424 3775);
FORCEPROP 2 LAST $XR0 95 
J 0
(1424 3775);
DISPLAY 0.638298 (1424 3775);
PAINT MONO (1424 3775);
DISPLAY INVISIBLE (1424 3775);
FORCEADD RES..2
(2350 4200);
FORCEPROP 1 LASTPIN (2350 4300) $PN 1
J 0
(2355 4262);
DISPLAY 0.617021 (2355 4262);
PAINT ORANGE (2355 4262);
FORCEPROP 1 LASTPIN (2350 4100) $PN 2
J 0
(2355 4110);
DISPLAY 0.617021 (2355 4110);
PAINT ORANGE (2355 4110);
FORCEPROP 1 LAST PACK_TYPE 0402
J 0
(2390 4025);
DISPLAY 0.617021 (2390 4025);
PAINT SKYBLUE (2390 4025);
FORCEPROP 1 LAST MATERIAL CHIP
J 0
(2390 4125);
DISPLAY 0.617021 (2390 4125);
PAINT SKYBLUE (2390 4125);
FORCEPROP 1 LAST PART_NUMBER G21796-072
J 0
(2390 4075);
DISPLAY 0.617021 (2390 4075);
PAINT BLUE (2390 4075);
FORCEPROP 1 LAST WATTAGE 1/16W
J 0
(2390 4175);
DISPLAY 0.617021 (2390 4175);
PAINT SKYBLUE (2390 4175);
FORCEPROP 1 LAST TOLERANCE 1%
J 0
(2395 4225);
DISPLAY 0.617021 (2395 4225);
PAINT SKYBLUE (2395 4225);
FORCEPROP 1 LAST VALUE 4.75K
J 0
(2395 4275);
DISPLAY 0.617021 (2395 4275);
PAINT SKYBLUE (2395 4275);
FORCEPROP 1 LAST LOCATION R7E21
J 0
(2395 4325);
DISPLAY 0.617021 (2395 4325);
PAINT AQUA (2395 4325);
FORCEPROP 2 LAST CDS_LIB mstr_discrete
J 0
(2350 4200);
PAINT ORANGE (2350 4200);
DISPLAY INVISIBLE (2350 4200);
FORCEPROP 1 LAST PATH I343
J 0
(2400 4375);
DISPLAY 0.978723 (2400 4375);
PAINT WHITE (2400 4375);
DISPLAY INVISIBLE (2400 4375);
FORCEPROP 0 LAST ROOM IO_SLOT
J 0
(2400 4425);
DISPLAY 1.021277 (2400 4425);
PAINT ORANGE (2400 4425);
DISPLAY INVISIBLE (2400 4425);
FORCEPROP 2 LAST SEC 1
J 0
(2400 4425);
DISPLAY 0.680851 (2400 4425);
PAINT MONO (2400 4425);
DISPLAY INVISIBLE (2400 4425);
FORCEPROP 2 LAST SEC_TYPE 0402
J 0
(2400 4425);
DISPLAY 1.021277 (2400 4425);
PAINT ORANGE (2400 4425);
DISPLAY INVISIBLE (2400 4425);
FORCEADD P3V3..1
(2350 4400);
FORCEPROP 3 LASTPIN (2350 4350) SIG_NAME P3V3\g
J 0
(2360 4360);
DISPLAY 0.659574 (2360 4360);
PAINT MONO (2360 4360);
DISPLAY INVISIBLE (2360 4360);
FORCEPROP 1 LAST HDL_POWER P3V3
J 0
(2025 4275);
DISPLAY 0.872340 (2025 4275);
PAINT ORANGE (2025 4275);
DISPLAY INVISIBLE (2025 4275);
FORCEPROP 1 LAST PATH I344
J 0
(2395 4402);
DISPLAY 0.340426 (2395 4402);
PAINT GREEN (2395 4402);
DISPLAY INVISIBLE (2395 4402);
FORCEPROP 1 LAST BODY_TYPE PLUMBING
J 0
(2305 4357);
DISPLAY 0.340426 (2305 4357);
PAINT GREEN (2305 4357);
DISPLAY INVISIBLE (2305 4357);
FORCEPROP 1 LAST SIZE 1B
J 0
(2395 4422);
DISPLAY 0.340426 (2395 4422);
PAINT GREEN (2395 4422);
DISPLAY INVISIBLE (2395 4422);
FORCEPROP 2 LAST CDS_LIB mstr_symbols
J 0
(2350 4400);
PAINT ORANGE (2350 4400);
DISPLAY INVISIBLE (2350 4400);
FORCEPROP 1 LAST VOLTAGE 3.3V
J 0
(2305 4357);
DISPLAY 0.340426 (2305 4357);
PAINT SKYBLUE (2305 4357);
DISPLAY INVISIBLE (2305 4357);
FORCEADD TAP..1
(1500 1875);
FORCEPROP 3 LASTPIN (1450 1875) SIG_NAME P3E_CPU0_PE1_PCH_CON_RXN<8>
J 0
(1460 1885);
DISPLAY 0.659574 (1460 1885);
PAINT MONO (1460 1885);
DISPLAY INVISIBLE (1460 1885);
FORCEPROP 1 LASTPIN (1450 1875) BN 8
J 0
(1438 1883);
DISPLAY 0.617021 (1438 1883);
PAINT GREEN (1438 1883);
FORCEPROP 1 LAST PATH I345
J 0
(1498 1875);
DISPLAY 0.872340 (1498 1875);
PAINT GREEN (1498 1875);
DISPLAY INVISIBLE (1498 1875);
FORCEPROP 1 LAST HDL_TAP TRUE
J 0
(1825 1750);
DISPLAY 0.638298 (1825 1750);
PAINT GREEN (1825 1750);
DISPLAY INVISIBLE (1825 1750);
FORCEPROP 1 LAST BODY_TYPE PLUMBING
J 0
(1500 1925);
DISPLAY 0.638298 (1500 1925);
PAINT GREEN (1500 1925);
DISPLAY INVISIBLE (1500 1925);
FORCEPROP 2 LAST CDS_LIB mstr_standard
J 0
(1500 1875);
PAINT MONO (1500 1875);
DISPLAY INVISIBLE (1500 1875);
FORCEADD TAP..1
(1500 2025);
FORCEPROP 3 LASTPIN (1450 2025) SIG_NAME P3E_CPU0_PE1_PCH_CON_RXN<9>
J 0
(1460 2035);
DISPLAY 0.659574 (1460 2035);
PAINT MONO (1460 2035);
DISPLAY INVISIBLE (1460 2035);
FORCEPROP 1 LASTPIN (1450 2025) BN 9
J 0
(1438 2033);
DISPLAY 0.617021 (1438 2033);
PAINT GREEN (1438 2033);
FORCEPROP 2 LAST CDS_LIB mstr_standard
J 0
(1500 2025);
PAINT MONO (1500 2025);
DISPLAY INVISIBLE (1500 2025);
FORCEPROP 1 LAST HDL_TAP TRUE
J 0
(1825 1900);
DISPLAY 0.638298 (1825 1900);
PAINT GREEN (1825 1900);
DISPLAY INVISIBLE (1825 1900);
FORCEPROP 1 LAST BODY_TYPE PLUMBING
J 0
(1500 2075);
DISPLAY 0.638298 (1500 2075);
PAINT GREEN (1500 2075);
DISPLAY INVISIBLE (1500 2075);
FORCEPROP 1 LAST PATH I346
J 0
(1498 2025);
DISPLAY 0.872340 (1498 2025);
PAINT GREEN (1498 2025);
DISPLAY INVISIBLE (1498 2025);
FORCEADD TAP..1
(1350 1975);
FORCEPROP 3 LASTPIN (1300 1975) SIG_NAME P3E_CPU0_PE1_PCH_CON_RXP<9>
J 0
(1310 1985);
DISPLAY 0.659574 (1310 1985);
PAINT MONO (1310 1985);
DISPLAY INVISIBLE (1310 1985);
FORCEPROP 1 LASTPIN (1300 1975) BN 9
J 0
(1288 1983);
DISPLAY 0.617021 (1288 1983);
PAINT GREEN (1288 1983);
FORCEPROP 1 LAST HDL_TAP TRUE
J 0
(1675 1850);
DISPLAY 0.638298 (1675 1850);
PAINT GREEN (1675 1850);
DISPLAY INVISIBLE (1675 1850);
FORCEPROP 2 LAST CDS_LIB mstr_standard
J 0
(1350 1975);
PAINT MONO (1350 1975);
DISPLAY INVISIBLE (1350 1975);
FORCEPROP 1 LAST BODY_TYPE PLUMBING
J 0
(1350 2025);
DISPLAY 0.638298 (1350 2025);
PAINT GREEN (1350 2025);
DISPLAY INVISIBLE (1350 2025);
FORCEPROP 1 LAST PATH I347
J 0
(1348 1975);
DISPLAY 0.872340 (1348 1975);
PAINT GREEN (1348 1975);
DISPLAY INVISIBLE (1348 1975);
FORCEADD OFFPAGE..4
(2325 3625);
FORCEPROP 2 LAST $XR0 138 
J 0
(2511 3625);
DISPLAY 0.638298 (2511 3625);
PAINT MONO (2511 3625);
FORCEPROP 1 LAST OFFPAGE TRUE
J 0
(2650 3500);
PAINT GREEN (2650 3500);
DISPLAY INVISIBLE (2650 3500);
FORCEPROP 1 LAST COMMENT_BODY TRUE
J 0
(2300 3525);
DISPLAY 0.638298 (2300 3525);
PAINT GREEN (2300 3525);
DISPLAY INVISIBLE (2300 3525);
FORCEPROP 2 LAST PATH I348
J 0
(2500 3700);
DISPLAY 1.021277 (2500 3700);
PAINT ORANGE (2500 3700);
DISPLAY INVISIBLE (2500 3700);
FORCEPROP 2 LAST CDS_LIB mstr_standard
J 0
(2325 3625);
PAINT MONO (2325 3625);
DISPLAY INVISIBLE (2325 3625);
FORCEADD OFFPAGE..4
(2325 3575);
FORCEPROP 2 LAST $XR0 138 
J 0
(2511 3575);
DISPLAY 0.638298 (2511 3575);
PAINT MONO (2511 3575);
FORCEPROP 2 LAST CDS_LIB mstr_standard
J 0
(2325 3575);
PAINT MONO (2325 3575);
DISPLAY INVISIBLE (2325 3575);
FORCEPROP 2 LAST PATH I349
J 0
(2500 3650);
DISPLAY 1.021277 (2500 3650);
PAINT ORANGE (2500 3650);
DISPLAY INVISIBLE (2500 3650);
FORCEPROP 1 LAST COMMENT_BODY TRUE
J 0
(2300 3475);
DISPLAY 0.638298 (2300 3475);
PAINT GREEN (2300 3475);
DISPLAY INVISIBLE (2300 3475);
FORCEPROP 1 LAST OFFPAGE TRUE
J 0
(2650 3450);
PAINT GREEN (2650 3450);
DISPLAY INVISIBLE (2650 3450);
FORCEADD RES..1
(-2275 4625);
FORCEPROP 1 LASTPIN (-2375 4625) $PN 1
J 0
(-2363 4637);
DISPLAY 0.617021 (-2363 4637);
PAINT ORANGE (-2363 4637);
FORCEPROP 1 LAST VALUE 20.0
J 2
(-2325 4575);
DISPLAY 0.617021 (-2325 4575);
PAINT SKYBLUE (-2325 4575);
FORCEPROP 1 LAST WATTAGE 1/16W
J 0
(-1675 4575);
DISPLAY 0.617021 (-1675 4575);
PAINT SKYBLUE (-1675 4575);
FORCEPROP 1 LAST LOCATION R2U35
J 0
(-2600 4575);
DISPLAY 0.617021 (-2600 4575);
PAINT AQUA (-2600 4575);
FORCEPROP 1 LAST TOLERANCE 1%
J 0
(-2200 4575);
DISPLAY 0.617021 (-2200 4575);
PAINT SKYBLUE (-2200 4575);
FORCEPROP 1 LASTPIN (-2175 4625) $PN 2
J 0
(-2213 4637);
DISPLAY 0.617021 (-2213 4637);
PAINT ORANGE (-2213 4637);
FORCEPROP 1 LAST PACK_TYPE 0402
J 0
(-1525 4575);
DISPLAY 0.617021 (-1525 4575);
PAINT SKYBLUE (-1525 4575);
FORCEPROP 1 LAST MATERIAL EMPTY
J 0
(-2100 4575);
DISPLAY 0.617021 (-2100 4575);
PAINT RED (-2100 4575);
FORCEPROP 1 LAST PART_NUMBER G21796-173
J 0
(-1925 4575);
DISPLAY 0.617021 (-1925 4575);
PAINT BLUE (-1925 4575);
FORCEPROP 1 LAST PATH I350
J 0
(-2325 4775);
DISPLAY 0.978723 (-2325 4775);
PAINT WHITE (-2325 4775);
DISPLAY INVISIBLE (-2325 4775);
FORCEPROP 2 LAST CDS_LIB mstr_discrete
J 0
(-2275 4625);
PAINT MONO (-2275 4625);
DISPLAY INVISIBLE (-2275 4625);
FORCEPROP 2 LAST $SEC 1
J 0
(-2325 4825);
PAINT MONO (-2325 4825);
DISPLAY INVISIBLE (-2325 4825);
FORCEPROP 2 LAST CDS_SEC 1
J 0
(-2325 4825);
PAINT MONO (-2325 4825);
DISPLAY INVISIBLE (-2325 4825);
FORCEPROP 0 LAST ROOM SMBUS
J 0
(-2025 4675);
DISPLAY 1.021277 (-2025 4675);
PAINT ORANGE (-2025 4675);
DISPLAY INVISIBLE (-2025 4675);
FORCEPROP 0 LAST SKU A
J 0
(-2025 4675);
DISPLAY 1.021277 (-2025 4675);
PAINT ORANGE (-2025 4675);
DISPLAY INVISIBLE (-2025 4675);
FORCEPROP 0 LAST BOM_COST SM_CONTROLLER
J 0
(-2025 4775);
DISPLAY 1.021277 (-2025 4775);
PAINT ORANGE (-2025 4775);
DISPLAY INVISIBLE (-2025 4775);
FORCEPROP 2 LAST CDS_LOCATION R2U35
J 0
(-2325 4700);
DISPLAY 0.617021 (-2325 4700);
PAINT AQUA (-2325 4700);
DISPLAY INVISIBLE (-2325 4700);
FORCEADD RES..1
(-2275 4375);
FORCEPROP 1 LAST VALUE 20.0
J 2
(-2325 4325);
DISPLAY 0.617021 (-2325 4325);
PAINT SKYBLUE (-2325 4325);
FORCEPROP 1 LAST TOLERANCE 1%
J 0
(-2200 4325);
DISPLAY 0.617021 (-2200 4325);
PAINT SKYBLUE (-2200 4325);
FORCEPROP 1 LASTPIN (-2375 4375) $PN 1
J 0
(-2363 4387);
DISPLAY 0.617021 (-2363 4387);
PAINT ORANGE (-2363 4387);
FORCEPROP 1 LAST LOCATION R2U36
J 0
(-2600 4325);
DISPLAY 0.617021 (-2600 4325);
PAINT AQUA (-2600 4325);
FORCEPROP 1 LASTPIN (-2175 4375) $PN 2
J 0
(-2213 4387);
DISPLAY 0.617021 (-2213 4387);
PAINT ORANGE (-2213 4387);
FORCEPROP 1 LAST PACK_TYPE 0402
J 0
(-1525 4325);
DISPLAY 0.617021 (-1525 4325);
PAINT SKYBLUE (-1525 4325);
FORCEPROP 1 LAST WATTAGE 1/16W
J 0
(-1675 4325);
DISPLAY 0.617021 (-1675 4325);
PAINT SKYBLUE (-1675 4325);
FORCEPROP 1 LAST PART_NUMBER G21796-173
J 0
(-1925 4325);
DISPLAY 0.617021 (-1925 4325);
PAINT BLUE (-1925 4325);
FORCEPROP 1 LAST MATERIAL EMPTY
J 0
(-2100 4325);
DISPLAY 0.617021 (-2100 4325);
PAINT RED (-2100 4325);
FORCEPROP 0 LAST BOM_COST SM_CONTROLLER
J 0
(-2025 4525);
DISPLAY 1.021277 (-2025 4525);
PAINT ORANGE (-2025 4525);
DISPLAY INVISIBLE (-2025 4525);
FORCEPROP 0 LAST SKU A
J 0
(-2025 4425);
DISPLAY 1.021277 (-2025 4425);
PAINT ORANGE (-2025 4425);
DISPLAY INVISIBLE (-2025 4425);
FORCEPROP 0 LAST ROOM SMBUS
J 0
(-2025 4425);
DISPLAY 1.021277 (-2025 4425);
PAINT ORANGE (-2025 4425);
DISPLAY INVISIBLE (-2025 4425);
FORCEPROP 2 LAST CDS_SEC 1
J 0
(-2325 4575);
PAINT MONO (-2325 4575);
DISPLAY INVISIBLE (-2325 4575);
FORCEPROP 2 LAST $SEC 1
J 0
(-2325 4575);
PAINT MONO (-2325 4575);
DISPLAY INVISIBLE (-2325 4575);
FORCEPROP 2 LAST CDS_LIB mstr_discrete
J 0
(-2275 4375);
PAINT MONO (-2275 4375);
DISPLAY INVISIBLE (-2275 4375);
FORCEPROP 1 LAST PATH I351
J 0
(-2325 4525);
DISPLAY 0.978723 (-2325 4525);
PAINT WHITE (-2325 4525);
DISPLAY INVISIBLE (-2325 4525);
FORCEPROP 2 LAST CDS_LOCATION R2U36
J 0
(-2325 4450);
DISPLAY 0.617021 (-2325 4450);
PAINT AQUA (-2325 4450);
DISPLAY INVISIBLE (-2325 4450);
FORCEADD OFFPAGE..6
(-3175 4625);
FORCEPROP 2 LAST $XR1 138 
J 0
(-3545 4589);
DISPLAY 0.638298 (-3545 4589);
PAINT MONO (-3545 4589);
FORCEPROP 2 LAST $XR0 119 
J 0
(-3545 4625);
DISPLAY 0.638298 (-3545 4625);
PAINT MONO (-3545 4625);
FORCEPROP 1 LAST COMMENT_BODY TRUE
J 0
(-3075 4550);
DISPLAY 0.872340 (-3075 4550);
PAINT GREEN (-3075 4550);
DISPLAY INVISIBLE (-3075 4550);
FORCEPROP 2 LAST CDS_LIB mstr_standard
J 0
(-3175 4625);
PAINT MONO (-3175 4625);
DISPLAY INVISIBLE (-3175 4625);
FORCEPROP 1 LAST OFFPAGE TRUE
J 0
(-2850 4500);
DISPLAY 0.872340 (-2850 4500);
PAINT GREEN (-2850 4500);
DISPLAY INVISIBLE (-2850 4500);
FORCEPROP 2 LAST PATH I352
J 0
(-3525 4675);
DISPLAY 1.021277 (-3525 4675);
PAINT ORANGE (-3525 4675);
DISPLAY INVISIBLE (-3525 4675);
FORCEADD OFFPAGE..1
(-3175 4375);
FORCEPROP 2 LAST $XR1 138 
J 0
(-3547 4339);
DISPLAY 0.638298 (-3547 4339);
PAINT MONO (-3547 4339);
FORCEPROP 2 LAST $XR0 119 
J 0
(-3547 4375);
DISPLAY 0.638298 (-3547 4375);
PAINT MONO (-3547 4375);
FORCEPROP 2 LAST CDS_LIB mstr_standard
J 0
(-3175 4375);
PAINT MONO (-3175 4375);
DISPLAY INVISIBLE (-3175 4375);
FORCEPROP 1 LAST COMMENT_BODY TRUE
J 0
(-3050 4275);
DISPLAY 0.872340 (-3050 4275);
PAINT GREEN (-3050 4275);
DISPLAY INVISIBLE (-3050 4275);
FORCEPROP 1 LAST OFFPAGE TRUE
J 0
(-2850 4250);
DISPLAY 0.872340 (-2850 4250);
PAINT GREEN (-2850 4250);
DISPLAY INVISIBLE (-2850 4250);
FORCEPROP 2 LAST PATH I353
J 0
(-3525 4425);
DISPLAY 1.021277 (-3525 4425);
PAINT ORANGE (-3525 4425);
DISPLAY INVISIBLE (-3525 4425);
FORCEADD P12V..1
(-3275 925);
FORCEPROP 3 LASTPIN (-3275 875) SIG_NAME P12V\g
J 0
(-3265 885);
DISPLAY 0.659574 (-3265 885);
PAINT MONO (-3265 885);
DISPLAY INVISIBLE (-3265 885);
FORCEPROP 1 LAST HDL_POWER P12V
J 0
(-3475 775);
DISPLAY 0.872340 (-3475 775);
PAINT ORANGE (-3475 775);
DISPLAY INVISIBLE (-3475 775);
FORCEPROP 1 LAST BODY_TYPE PLUMBING
J 0
(-3320 882);
DISPLAY 0.340426 (-3320 882);
PAINT GREEN (-3320 882);
DISPLAY INVISIBLE (-3320 882);
FORCEPROP 1 LAST PATH I4
J 0
(-3230 927);
DISPLAY 0.340426 (-3230 927);
PAINT GREEN (-3230 927);
DISPLAY INVISIBLE (-3230 927);
FORCEPROP 1 LAST VOLTAGE +12.
J 0
(-3275 925);
PAINT SKYBLUE (-3275 925);
DISPLAY INVISIBLE (-3275 925);
FORCEPROP 1 LAST SIZE 1B
J 0
(-3230 947);
DISPLAY 0.340426 (-3230 947);
PAINT GREEN (-3230 947);
DISPLAY INVISIBLE (-3230 947);
FORCEPROP 2 LAST CDS_LIB mstr_symbols
J 0
(-3275 925);
PAINT MONO (-3275 925);
DISPLAY INVISIBLE (-3275 925);
FORCEADD CAP_A..1
(-3275 1400);
FORCEPROP 1 LAST PACK_TYPE 0402V
J 0
(-3225 1200);
DISPLAY 0.617021 (-3225 1200);
PAINT SKYBLUE (-3225 1200);
FORCEPROP 1 LASTPIN (-3275 1300) $PN 2
J 0
(-3265 1280);
DISPLAY 0.617021 (-3265 1280);
PAINT ORANGE (-3265 1280);
FORCEPROP 1 LASTPIN (-3275 1500) $PN 1
J 0
(-3265 1480);
DISPLAY 0.617021 (-3265 1480);
PAINT ORANGE (-3265 1480);
FORCEPROP 1 LAST VALUE 0.1UF
J 0
(-3225 1450);
DISPLAY 0.617021 (-3225 1450);
PAINT SKYBLUE (-3225 1450);
FORCEPROP 1 LAST LOCATION C2U21
J 0
(-3225 1500);
DISPLAY 0.617021 (-3225 1500);
PAINT AQUA (-3225 1500);
FORCEPROP 1 LAST TOLERANCE 10%
J 0
(-3225 1350);
DISPLAY 0.617021 (-3225 1350);
PAINT SKYBLUE (-3225 1350);
FORCEPROP 1 LAST VOLTAGE 16V
J 0
(-3225 1400);
DISPLAY 0.617021 (-3225 1400);
PAINT SKYBLUE (-3225 1400);
FORCEPROP 1 LAST MATERIAL X7R
J 0
(-3225 1300);
DISPLAY 0.617021 (-3225 1300);
PAINT SKYBLUE (-3225 1300);
FORCEPROP 1 LAST PART_NUMBER A36096-030
J 0
(-3225 1250);
DISPLAY 0.617021 (-3225 1250);
PAINT BLUE (-3225 1250);
FORCEPROP 2 LAST CDS_LOCATION C2U21
J 0
(-3225 1500);
DISPLAY 0.617021 (-3225 1500);
PAINT AQUA (-3225 1500);
DISPLAY INVISIBLE (-3225 1500);
FORCEPROP 2 LAST CDS_LIB dev_discrete
J 0
(-3275 1400);
PAINT ORANGE (-3275 1400);
DISPLAY INVISIBLE (-3275 1400);
FORCEPROP 1 LAST PATH I5
J 0
(-3225 1550);
DISPLAY 0.978723 (-3225 1550);
PAINT WHITE (-3225 1550);
DISPLAY INVISIBLE (-3225 1550);
FORCEPROP 0 LAST ROOM IO_SLOT
J 0
(-3225 1600);
DISPLAY 1.021277 (-3225 1600);
PAINT ORANGE (-3225 1600);
DISPLAY INVISIBLE (-3225 1600);
FORCEPROP 2 LAST CDS_SEC 1
J 0
(-3225 1550);
PAINT ORANGE (-3225 1550);
DISPLAY INVISIBLE (-3225 1550);
FORCEPROP 2 LAST SEC 1
J 0
(-3225 1600);
DISPLAY 0.680851 (-3225 1600);
PAINT MONO (-3225 1600);
DISPLAY INVISIBLE (-3225 1600);
FORCEPROP 2 LAST SEC_TYPE 0402V
J 0
(-3225 1600);
DISPLAY 1.021277 (-3225 1600);
PAINT ORANGE (-3225 1600);
DISPLAY INVISIBLE (-3225 1600);
FORCEADD CAP_A..1
(-2875 1375);
FORCEPROP 1 LASTPIN (-2875 1275) $PN 2
J 0
(-2865 1255);
DISPLAY 0.617021 (-2865 1255);
PAINT ORANGE (-2865 1255);
FORCEPROP 1 LAST MATERIAL X7R
J 0
(-2825 1275);
DISPLAY 0.617021 (-2825 1275);
PAINT SKYBLUE (-2825 1275);
FORCEPROP 1 LAST TOLERANCE 10%
J 0
(-2825 1325);
DISPLAY 0.617021 (-2825 1325);
PAINT SKYBLUE (-2825 1325);
FORCEPROP 1 LAST PACK_TYPE 0402V
J 0
(-2825 1175);
DISPLAY 0.617021 (-2825 1175);
PAINT SKYBLUE (-2825 1175);
FORCEPROP 1 LAST PART_NUMBER A36096-030
J 0
(-2825 1225);
DISPLAY 0.617021 (-2825 1225);
PAINT BLUE (-2825 1225);
FORCEPROP 1 LAST VALUE 0.1UF
J 0
(-2825 1425);
DISPLAY 0.617021 (-2825 1425);
PAINT SKYBLUE (-2825 1425);
FORCEPROP 1 LAST VOLTAGE 16V
J 0
(-2825 1375);
DISPLAY 0.617021 (-2825 1375);
PAINT SKYBLUE (-2825 1375);
FORCEPROP 1 LAST LOCATION C2U25
J 0
(-2825 1475);
DISPLAY 0.617021 (-2825 1475);
PAINT AQUA (-2825 1475);
FORCEPROP 1 LASTPIN (-2875 1475) $PN 1
J 0
(-2865 1455);
DISPLAY 0.617021 (-2865 1455);
PAINT ORANGE (-2865 1455);
FORCEPROP 2 LAST CDS_LIB dev_discrete
J 0
(-2875 1375);
PAINT ORANGE (-2875 1375);
DISPLAY INVISIBLE (-2875 1375);
FORCEPROP 2 LAST CDS_LOCATION C2U25
J 0
(-2825 1475);
DISPLAY 0.617021 (-2825 1475);
PAINT AQUA (-2825 1475);
DISPLAY INVISIBLE (-2825 1475);
FORCEPROP 1 LAST PATH I7
J 0
(-2825 1525);
DISPLAY 0.978723 (-2825 1525);
PAINT WHITE (-2825 1525);
DISPLAY INVISIBLE (-2825 1525);
FORCEPROP 2 LAST CDS_SEC 1
J 0
(-2825 1525);
PAINT ORANGE (-2825 1525);
DISPLAY INVISIBLE (-2825 1525);
FORCEPROP 0 LAST ROOM IO_SLOT
J 0
(-2825 1575);
DISPLAY 1.021277 (-2825 1575);
PAINT ORANGE (-2825 1575);
DISPLAY INVISIBLE (-2825 1575);
FORCEPROP 2 LAST SEC_TYPE 0402V
J 0
(-2825 1575);
DISPLAY 1.021277 (-2825 1575);
PAINT ORANGE (-2825 1575);
DISPLAY INVISIBLE (-2825 1575);
FORCEPROP 2 LAST SEC 1
J 0
(-2825 1575);
DISPLAY 0.680851 (-2825 1575);
PAINT MONO (-2825 1575);
DISPLAY INVISIBLE (-2825 1575);
FORCEADD DNS..2
(-2270 4370);
PAINT RED (-2270 4370);
FORCEPROP 2 LAST CDS_LIB mstr_misc
J 0
(-2270 4370);
PAINT ORANGE (-2270 4370);
DISPLAY INVISIBLE (-2270 4370);
FORCEPROP 1 LAST COMMENT_BODY TRUE
R 1
J 0
(-2195 4145);
DISPLAY 0.872340 (-2195 4145);
PAINT GREEN (-2195 4145);
DISPLAY INVISIBLE (-2195 4145);
FORCEADD DNS..2
(-2270 4620);
PAINT RED (-2270 4620);
FORCEPROP 1 LAST COMMENT_BODY TRUE
R 1
J 0
(-2195 4395);
DISPLAY 0.872340 (-2195 4395);
PAINT GREEN (-2195 4395);
DISPLAY INVISIBLE (-2195 4395);
FORCEPROP 2 LAST CDS_LIB mstr_misc
J 0
(-2270 4620);
PAINT ORANGE (-2270 4620);
DISPLAY INVISIBLE (-2270 4620);
FORCEADD CAD_NOTE..1
(-3175 4850);
FORCEPROP 0 LAST L1 USE SHARED PADS FOR THESE RESISTORS
J 0
(-3325 4750);
DISPLAY 0.808511 (-3325 4750);
PAINT ORANGE (-3325 4750);
FORCEPROP 0 LAST L2 PLACE CLOSE TO X24 SLOT
J 0
(-3325 4700);
DISPLAY 0.808511 (-3325 4700);
PAINT ORANGE (-3325 4700);
FORCEPROP 1 LAST COMMENT_BODY TRUE
J 0
(-3150 4950);
DISPLAY 0.978723 (-3150 4950);
PAINT ORANGE (-3150 4950);
DISPLAY INVISIBLE (-3150 4950);
FORCEPROP 2 LAST CDS_LIB mstr_symbols
J 0
(-3175 4850);
PAINT MONO (-3175 4850);
DISPLAY INVISIBLE (-3175 4850);
FORCEADD INTEL_CORP_BPAGE..1
(4400 50);
FORCEPROP 1 LAST CDS_CON_LAST_MODIFIED Fri Jun 16 17:48:43 2017
J 0
(2975 375);
PAINT ORANGE (2975 375);
DISPLAY INVISIBLE (2975 375);
FORCEPROP 1 LAST CUSTOM_TXT_CDS <CURRENT_DESIGN_SHEET> OF <TOTAL_DESIGN_SHEETS>
J 0
(3900 75);
PAINT ORANGE (3900 75);
FORCEPROP 1 LAST CUSTOM_TXT_CDS <CON_LAST_MODIFIED>
J 0
(400 150);
PAINT ORANGE (400 150);
FORCEPROP 2 LAST CUSTOM_TXT_CDS <XR_PAGE_TITLE>
J 0
(-3490 5300);
DISPLAY 0.638298 (-3490 5300);
PAINT PINK (-3490 5300);
DISPLAY INVISIBLE (-3490 5300);
FORCEPROP 1 LAST SCH_TITLE X24 SLOT (1 OF 2)
J 0
(-3550 100);
DISPLAY 1.212766 (-3550 100);
PAINT ORANGE (-3550 100);
FORCEPROP 2 LAST PAGE_BORDER TRUE
J 0
(-3490 5300);
DISPLAY 0.638298 (-3490 5300);
PAINT PINK (-3490 5300);
DISPLAY INVISIBLE (-3490 5300);
FORCEPROP 1 LAST COMMENT_BODY TRUE
J 0
(4412 62);
DISPLAY 0.468085 (4412 62);
PAINT GREEN (4412 62);
DISPLAY INVISIBLE (4412 62);
FORCEPROP 2 LAST CDS_LIB mstr_symbols
J 0
(4400 50);
PAINT MONO (4400 50);
DISPLAY INVISIBLE (4400 50);
FORCEPROP 2 LAST CDS_XR_PAGE_TITLE CR-108 : @BASEBOARD_FAB2_LIB.BASEBOARD_FAB2(SCH_1):PAGE108
J 0
(-3490 5300);
DISPLAY 0.638298 (-3490 5300);
PAINT PINK (-3490 5300);
DISPLAY INVISIBLE (-3490 5300);
WIRE 16 -1 (1375 4625)(1375 4325);
WIRE 16 -1 (1375 4325)(1375 4275);
WIRE 16 -1 (1375 4325)(800 4325);
WIRE 16 -1 (1375 4275)(1375 4225);
WIRE 16 -1 (1375 4275)(800 4275);
WIRE 16 -1 (1375 4225)(1375 4175);
WIRE 16 -1 (1375 4225)(800 4225);
WIRE 16 -1 (1375 4175)(1375 4125);
WIRE 16 -1 (1375 4175)(800 4175);
WIRE 16 -1 (1375 4125)(1375 4075);
WIRE 16 -1 (1375 4125)(800 4125);
WIRE 16 -1 (1375 4075)(800 4075);
WIRE 16 -1 (-350 4675)(-350 4325);
WIRE 16 -1 (-350 4275)(-350 4325);
WIRE 16 -1 (-350 4325)(200 4325);
WIRE 16 -1 (-350 4275)(-350 4225);
WIRE 16 -1 (-350 4275)(200 4275);
WIRE 16 -1 (-350 4225)(-350 4175);
WIRE 16 -1 (-350 4225)(200 4225);
WIRE 16 -1 (-350 4175)(-350 4125);
WIRE 16 -1 (-350 4175)(200 4175);
WIRE 16 -1 (-350 4125)(-350 4075);
WIRE 16 -1 (-350 4125)(200 4125);
WIRE 16 -1 (-350 4075)(200 4075);
WIRE 16 -1 (-100 1650)(-100 1825);
WIRE 16 -1 (-100 1825)(-100 1975);
WIRE 16 -1 (-100 1825)(200 1825);
WIRE 16 -1 (-100 2125)(-100 1975);
WIRE 16 -1 (200 1975)(-100 1975);
WIRE 16 -1 (-100 2275)(-100 2125);
WIRE 16 -1 (200 2125)(-100 2125);
WIRE 16 -1 (-100 2275)(-100 2425);
WIRE 16 -1 (200 2275)(-100 2275);
WIRE 16 -1 (-100 2575)(-100 2425);
WIRE 16 -1 (200 2425)(-100 2425);
WIRE 16 -1 (-100 2725)(-100 2575);
WIRE 16 -1 (200 2575)(-100 2575);
WIRE 16 -1 (-100 2825)(-100 2725);
WIRE 16 -1 (200 2725)(-100 2725);
WIRE 16 -1 (-100 2975)(-100 2825);
WIRE 16 -1 (200 2825)(-100 2825);
WIRE 16 -1 (-100 2975)(-100 3125);
WIRE 16 -1 (200 2975)(-100 2975);
WIRE 16 -1 (-100 3275)(-100 3125);
WIRE 16 -1 (200 3125)(-100 3125);
WIRE 16 -1 (-100 3425)(-100 3275);
WIRE 16 -1 (200 3275)(-100 3275);
WIRE 16 -1 (-100 3425)(-100 3575);
WIRE 16 -1 (200 3425)(-100 3425);
WIRE 16 -1 (-100 3575)(-100 4025);
WIRE 16 -1 (-100 3575)(200 3575);
WIRE 16 -1 (-100 4025)(200 4025);
WIRE 16 -1 (-525 4050)(-525 3825);
WIRE 16 -1 (-525 3825)(-525 3775);
WIRE 16 -1 (200 3825)(-525 3825);
WIRE 16 -1 (-525 3775)(200 3775);
WIRE 16 -1 (1050 1650)(1050 1825);
WIRE 16 -1 (1050 1825)(1050 1925);
WIRE 16 -1 (800 1825)(1050 1825);
WIRE 16 -1 (1050 2075)(1050 1925);
WIRE 16 -1 (1050 1925)(800 1925);
WIRE 16 -1 (1050 2075)(1050 2225);
WIRE 16 -1 (1050 2075)(800 2075);
WIRE 16 -1 (1050 2375)(1050 2225);
WIRE 16 -1 (1050 2225)(800 2225);
WIRE 16 -1 (1050 2375)(1050 2525);
WIRE 16 -1 (1050 2375)(800 2375);
WIRE 16 -1 (1050 2675)(1050 2525);
WIRE 16 -1 (1050 2525)(800 2525);
WIRE 16 -1 (1050 2775)(1050 2675);
WIRE 16 -1 (1050 2675)(800 2675);
WIRE 16 -1 (1050 2925)(1050 2775);
WIRE 16 -1 (1050 2775)(800 2775);
WIRE 16 -1 (1050 3075)(1050 2925);
WIRE 16 -1 (1050 2925)(800 2925);
WIRE 16 -1 (1050 3075)(1050 3225);
WIRE 16 -1 (1050 3075)(800 3075);
WIRE 16 -1 (1050 3375)(1050 3225);
WIRE 16 -1 (1050 3225)(800 3225);
WIRE 16 -1 (1050 3525)(1050 3375);
WIRE 16 -1 (1050 3375)(800 3375);
WIRE 16 -1 (1050 3525)(1050 3725);
WIRE 16 -1 (1050 3525)(800 3525);
WIRE 16 -1 (1050 3725)(1050 4025);
WIRE 16 -1 (1050 3725)(800 3725);
WIRE 16 -1 (1050 4025)(800 4025);
WIRE 16 -1 (1600 4625)(1600 3825);
WIRE 16 -1 (1600 3825)(1600 3775);
WIRE 16 -1 (800 3825)(1600 3825);
WIRE 16 -1 (1600 3775)(800 3775);
WIRE 16 -1 (-2875 400)(-2875 350);
WIRE 16 -1 (-3275 400)(-2875 400);
WIRE 16 -1 (-2875 400)(-2875 550);
WIRE 16 -1 (-3275 575)(-3275 400);
WIRE 16 -1 (-3275 1575)(-3275 1600);
WIRE 16 -1 (-3275 1575)(-2875 1575);
WIRE 16 -1 (-3275 1500)(-3275 1575);
WIRE 16 -1 (-2875 1575)(-2875 1475);
WIRE 16 -1 (-2875 1100)(-2875 1025);
WIRE 16 -1 (-2875 1100)(-3275 1100);
WIRE 16 -1 (-2875 1275)(-2875 1100);
WIRE 16 -1 (-3275 1100)(-3275 1300);
WIRE 16 -1 (-25 3725)(-25 4575);
WIRE 16 -1 (200 3725)(-25 3725);
WIRE 16 -1 (-1950 1075)(-1950 1000);
WIRE 16 -1 (-1950 1075)(-2350 1075);
WIRE 16 -1 (-1950 1250)(-1950 1075);
WIRE 16 -1 (-2350 1075)(-2350 1275);
WIRE 16 -1 (-2350 1550)(-2350 1575);
WIRE 16 -1 (-2350 1550)(-1950 1550);
WIRE 16 -1 (-2350 1475)(-2350 1550);
WIRE 16 -1 (-1950 1550)(-1950 1450);
WIRE 16 -1 (2350 4350)(2350 4300);
WIRE 16 -1 (-3275 875)(-3275 850);
WIRE 16 -1 (-3275 850)(-2875 850);
WIRE 16 -1 (-3275 850)(-3275 775);
WIRE 16 -1 (-2875 850)(-2875 750);
WIRE 17 -1 (-600 2100)(-600 1950);
WIRE 17 -1 (-600 2250)(-600 2100);
WIRE 17 -1 (-600 2400)(-600 2250);
WIRE 17 -1 (-600 2550)(-600 2400);
WIRE 17 -1 (-600 2700)(-600 2550);
WIRE 17 -1 (-600 2900)(-600 2700);
WIRE 17 -1 (-600 3075)(-1950 3075);
FORCEPROP 2 LAST SIG_NAME P3E_CPU0_PE1_PCH_CON_TXN<15:8>
J 0
(-1890 3073);
DISPLAY 0.680851 (-1890 3073);
PAINT ORANGE (-1890 3073);
WIRE 17 -1 (-600 3075)(-600 2900);
WIRE 17 -1 (-600 3100)(-600 3075);
WIRE 17 -1 (-800 2050)(-800 1900);
WIRE 17 -1 (-800 2200)(-800 2050);
WIRE 17 -1 (-800 2350)(-800 2200);
WIRE 17 -1 (-800 2500)(-800 2350);
WIRE 17 -1 (-800 2650)(-800 2500);
WIRE 17 -1 (-800 2950)(-800 2650);
WIRE 17 -1 (-800 3050)(-800 2950);
WIRE 17 -1 (-1950 3125)(-800 3125);
FORCEPROP 2 LAST SIG_NAME P3E_CPU0_PE1_PCH_CON_TXP<15:8>
J 0
(-1890 3133);
DISPLAY 0.680851 (-1890 3133);
PAINT ORANGE (-1890 3133);
WIRE 17 -1 (-800 3125)(-800 3050);
WIRE 3 -1 (1400 2150)(1400 2000);
WIRE 3 -1 (1400 2300)(1400 2150);
WIRE 3 -1 (1400 3075)(2800 3075);
FORCEPROP 2 LAST SIG_NAME P3E_CPU0_PE1_PCH_CON_RXP<15:8>
J 0
(1615 3085);
DISPLAY 0.680851 (1615 3085);
PAINT ORANGE (1615 3085);
WIRE 3 -1 (1400 3075)(1400 3000);
WIRE 3 -1 (1400 2450)(1400 2300);
WIRE 3 -1 (1400 2600)(1400 2450);
WIRE 3 -1 (1400 3000)(1400 2850);
WIRE 3 -1 (1400 2850)(1400 2600);
WIRE 17 -1 (1550 3050)(1550 2975);
WIRE 17 -1 (1550 2975)(2800 2975);
FORCEPROP 2 LAST SIG_NAME P3E_CPU0_PE1_PCH_CON_RXN<15:8>
J 0
(1615 2985);
DISPLAY 0.680851 (1615 2985);
PAINT ORANGE (1615 2985);
WIRE 17 -1 (1550 2900)(1550 2975);
WIRE 17 -1 (1550 2900)(1550 2650);
WIRE 17 -1 (1550 2650)(1550 2500);
WIRE 17 -1 (1550 1900)(1550 2050);
WIRE 17 -1 (1550 2050)(1550 2200);
WIRE 17 -1 (1550 2500)(1550 2350);
WIRE 17 -1 (1550 2350)(1550 2200);
WIRE 3 2175 (-2950 1775)(3375 1775);
WIRE 3 2175 (3375 3550)(3375 1775);
WIRE 3 2175 (-2950 3550)(-2950 1775);
WIRE 3 2175 (-2950 3550)(3375 3550);
WIRE 16 -1 (-1950 3975)(200 3975);
FORCEPROP 2 LAST SIG_NAME SMB_SLOTX24_STBY_LVC3_SDA_R2
J 0
(-1885 3985);
DISPLAY 0.638298 (-1885 3985);
PAINT ORANGE (-1885 3985);
WIRE 16 -1 (800 3275)(2800 3275);
FORCEPROP 0 LAST SIG_NAME CLK_100M_PCH_SLOTX24_S1_DN
J 0
(1615 3285);
DISPLAY 0.617021 (1615 3285);
PAINT ORANGE (1615 3285);
WIRE 16 -1 (800 3125)(2800 3125);
FORCEPROP 0 LAST SIG_NAME CLK_100M_PCH_SLOTX24_S2_DN
J 0
(1615 3135);
DISPLAY 0.617021 (1615 3135);
PAINT ORANGE (1615 3135);
WIRE 16 -1 (-1000 3625)(200 3625);
FORCEPROP 2 LAST SIG_NAME RST_PCIE_RISER1_PERST_R_N
J 0
(-885 3635);
DISPLAY 0.638298 (-885 3635);
PAINT ORANGE (-885 3635);
FORCEPROP 2 LASTPROP $XRERR UNIQUE?
J 0
(-1125 3635);
DISPLAY 0.638298 (-1125 3635);
PAINT MONO (-1125 3635);
DISPLAY INVISIBLE (-1125 3635);
WIRE 16 -1 (200 3675)(-1950 3675);
FORCEPROP 2 LAST SIG_NAME PU_PCH_TLS_ENABLE_STRAP
J 0
(-1885 3685);
DISPLAY 0.638298 (-1885 3685);
PAINT ORANGE (-1885 3685);
WIRE 16 -1 (-1800 4375)(-2175 4375);
WIRE 16 -1 (-2175 4250)(-1800 4250);
WIRE 16 -1 (-1800 4250)(-1800 4375);
WIRE 16 -1 (-1800 4250)(-925 4250);
FORCEPROP 2 LAST SIG_NAME SMB_SLOTX24_STBY_LVC3_SCL_R2
J 0
(-1710 4260);
DISPLAY 0.617021 (-1710 4260);
PAINT ORANGE (-1710 4260);
WIRE 16 -1 (-1950 3325)(200 3325);
FORCEPROP 0 LAST SIG_NAME CLK_100M_PCH_SLOTX24_S0_DN
J 0
(-1885 3335);
DISPLAY 0.617021 (-1885 3335);
PAINT ORANGE (-1885 3335);
WIRE 16 -1 (-3125 4500)(-2375 4500);
FORCEPROP 2 LAST SIG_NAME SMB_SLOTX24_BMC_STBY_LVC3_SDA
J 0
(-3100 4510);
DISPLAY 0.617021 (-3100 4510);
PAINT ORANGE (-3100 4510);
WIRE 16 3135 (-3425 4050)(-2150 4050);
WIRE 16 3135 (-3425 4950)(-3425 4050);
WIRE 16 3135 (-2150 4050)(-2150 4950);
WIRE 16 3135 (-2150 4950)(-3425 4950);
WIRE 16 -1 (200 3875)(-1950 3875);
FORCEPROP 2 LAST SIG_NAME FM_SLT_CFG0
J 0
(-1885 3885);
DISPLAY 0.638298 (-1885 3885);
PAINT ORANGE (-1885 3885);
WIRE 16 -1 (-250 3475)(200 3475);
WIRE 16 -1 (-250 3425)(-250 3475);
WIRE 16 -1 (-1950 3425)(-250 3425);
FORCEPROP 0 LAST SIG_NAME CLK_100M_PCH_SLOTX24_S5_DN
J 0
(-1885 3435);
DISPLAY 0.617021 (-1885 3435);
PAINT ORANGE (-1885 3435);
WIRE 16 -1 (-3125 4375)(-2375 4375);
FORCEPROP 2 LAST SIG_NAME SMB_SLOTX24_PCH_STBY_LVC3_SCL
J 0
(-3100 4385);
DISPLAY 0.617021 (-3100 4385);
PAINT ORANGE (-3100 4385);
WIRE 16 -1 (-3125 4625)(-2375 4625);
FORCEPROP 2 LAST SIG_NAME SMB_SLOTX24_PCH_STBY_LVC3_SDA
J 0
(-3100 4635);
DISPLAY 0.617021 (-3100 4635);
PAINT ORANGE (-3100 4635);
WIRE 16 -1 (-3125 4250)(-2375 4250);
FORCEPROP 2 LAST SIG_NAME SMB_SLOTX24_BMC_STBY_LVC3_SCL
J 0
(-3100 4260);
DISPLAY 0.617021 (-3100 4260);
PAINT ORANGE (-3100 4260);
WIRE 16 -1 (-1950 3925)(200 3925);
FORCEPROP 2 LAST SIG_NAME SMB_SLOTX24_STBY_LVC3_SCL_R2
J 0
(-1885 3935);
DISPLAY 0.638298 (-1885 3935);
PAINT ORANGE (-1885 3935);
WIRE 16 -1 (-1950 3625)(-1200 3625);
FORCEPROP 0 LAST SIG_NAME RST_PCIE_RISER1_PERST_N
J 0
(-1875 3635);
DISPLAY 0.617021 (-1875 3635);
PAINT ORANGE (-1875 3635);
WIRE 16 -1 (-325 3525)(200 3525);
WIRE 16 -1 (-325 3475)(-325 3525);
WIRE 16 -1 (-1950 3475)(-325 3475);
FORCEPROP 0 LAST SIG_NAME CLK_100M_PCH_SLOTX24_S5_DP
J 0
(-1885 3485);
DISPLAY 0.617021 (-1885 3485);
PAINT ORANGE (-1885 3485);
WIRE 16 -1 (-1800 4625)(-2175 4625);
WIRE 16 -1 (-2175 4500)(-1800 4500);
WIRE 16 -1 (-1800 4500)(-1800 4625);
WIRE 16 -1 (-1800 4500)(-925 4500);
FORCEPROP 2 LAST SIG_NAME SMB_SLOTX24_STBY_LVC3_SDA_R2
J 0
(-1710 4510);
DISPLAY 0.617021 (-1710 4510);
PAINT ORANGE (-1710 4510);
WIRE 3 682 (-1800 4725)(-1900 4725);
WIRE 3 682 (-1900 4700)(-2200 4700);
WIRE 3 682 (-1900 4700)(-1900 4725);
WIRE 3 682 (-1900 4400)(-2175 4400);
WIRE 3 682 (-1900 4400)(-1900 4700);
WIRE 16 -1 (800 3975)(2800 3975);
FORCEPROP 2 LAST SIG_NAME IRQ_OOB_MGMT_RISER_ALERT_N
J 0
(1615 3985);
DISPLAY 0.638298 (1615 3985);
PAINT ORANGE (1615 3985);
WIRE 16 -1 (800 3925)(2800 3925);
FORCEPROP 2 LAST SIG_NAME FM_SLT_CFG1
J 0
(1615 3935);
DISPLAY 0.638298 (1615 3935);
PAINT ORANGE (1615 3935);
WIRE 16 -1 (2700 3775)(2750 3775);
WIRE 16 -1 (2750 3775)(2750 3875);
WIRE 16 -1 (2750 3875)(2800 3875);
WIRE 16 -1 (800 3875)(2750 3875);
FORCEPROP 2 LAST SIG_NAME FM_PWRBRK_SLOT_N
J 0
(1615 3885);
DISPLAY 0.638298 (1615 3885);
PAINT ORANGE (1615 3885);
WIRE 16 -1 (800 3675)(2275 3675);
FORCEPROP 2 LAST SIG_NAME FM_PE_SLOTX24_WAKE_N
J 0
(1615 3685);
DISPLAY 0.638298 (1615 3685);
PAINT ORANGE (1615 3685);
WIRE 16 -1 (2275 3625)(800 3625);
FORCEPROP 2 LAST SIG_NAME SMB_HOST_STBY_LVC3_SDA_R5
J 0
(1440 3635);
DISPLAY 0.638298 (1440 3635);
PAINT ORANGE (1440 3635);
WIRE 16 -1 (2275 3575)(800 3575);
FORCEPROP 2 LAST SIG_NAME SMB_HOST_STBY_LVC3_SCL_R5
J 0
(1440 3585);
DISPLAY 0.638298 (1440 3585);
PAINT ORANGE (1440 3585);
WIRE 16 -1 (1900 3775)(2350 3775);
FORCEPROP 0 LAST SIG_NAME FM_PWRBRK_N
J 0
(1940 3785);
DISPLAY 0.617021 (1940 3785);
PAINT ORANGE (1940 3785);
WIRE 16 -1 (2350 4100)(2350 3775);
WIRE 16 -1 (2500 3775)(2350 3775);
WIRE 16 -1 (800 3475)(2800 3475);
FORCEPROP 0 LAST SIG_NAME CLK_100M_PCH_SLOTX24_S4_DP
J 0
(1615 3485);
DISPLAY 0.617021 (1615 3485);
PAINT ORANGE (1615 3485);
WIRE 16 -1 (800 3025)(1450 3025);
WIRE 3 682 (2800 3600)(2750 3600);
WIRE 3 682 (2800 3625)(2800 3600);
WIRE 3 682 (2800 3625)(2850 3625);
WIRE 3 682 (2800 3650)(2800 3625);
WIRE 3 682 (2750 3650)(2800 3650);
WIRE 16 -1 (-500 2375)(200 2375);
WIRE 16 -1 (-700 2175)(200 2175);
WIRE 16 -1 (-500 2075)(200 2075);
WIRE 16 -1 (200 2025)(-700 2025);
WIRE 16 -1 (-500 1925)(200 1925);
WIRE 16 -1 (800 2975)(1300 2975);
WIRE 16 -1 (800 2825)(1300 2825);
WIRE 16 -1 (-700 1875)(200 1875);
WIRE 16 -1 (800 1875)(1450 1875);
WIRE 16 -1 (800 2125)(1300 2125);
WIRE 16 -1 (800 2025)(1450 2025);
WIRE 2 -1 (800 1975)(1300 1975);
WIRE 16 -1 (1450 2625)(800 2625);
WIRE 16 -1 (800 2875)(1450 2875);
WIRE 16 -1 (800 2475)(1450 2475);
WIRE 16 -1 (800 2425)(1300 2425);
WIRE 16 -1 (800 2325)(1450 2325);
WIRE 16 -1 (800 2275)(1300 2275);
WIRE 16 -1 (800 2175)(1450 2175);
WIRE 16 -1 (-700 2625)(200 2625);
WIRE 16 -1 (200 2325)(-700 2325);
WIRE 16 -1 (-500 2225)(200 2225);
WIRE 16 -1 (200 2925)(-700 2925);
WIRE 16 -1 (-500 2875)(200 2875);
WIRE 3 682 (-1550 2700)(-1550 2850);
WIRE 3 682 (-900 2700)(-1550 2700);
WIRE 3 682 (-1550 2850)(-900 2850);
WIRE 3 682 (-900 2850)(-900 2700);
WIRE 3 682 (1600 2800)(1600 2650);
WIRE 3 682 (2300 2800)(1600 2800);
WIRE 3 682 (1600 2650)(2300 2650);
WIRE 3 682 (2300 2650)(2300 2800);
WIRE 16 -1 (800 2725)(2250 2725);
FORCEPROP 0 LAST SIG_NAME TP_SLOTX24_RSVD66
J 0
(1650 2735);
DISPLAY 0.617021 (1650 2735);
PAINT ORANGE (1650 2735);
FORCEPROP 2 LASTPROP $XRERR UNIQUE?
J 0
(2280 2725);
DISPLAY 0.638298 (2280 2725);
PAINT MONO (2280 2725);
DISPLAY INVISIBLE (2280 2725);
WIRE 16 -1 (800 3325)(2800 3325);
FORCEPROP 0 LAST SIG_NAME CLK_100M_PCH_SLOTX24_S1_DP
J 0
(1615 3335);
DISPLAY 0.617021 (1615 3335);
PAINT ORANGE (1615 3335);
WIRE 16 -1 (800 3425)(2800 3425);
FORCEPROP 0 LAST SIG_NAME CLK_100M_PCH_SLOTX24_S4_DN
J 0
(1615 3435);
DISPLAY 0.617021 (1615 3435);
PAINT ORANGE (1615 3435);
WIRE 16 -1 (800 3175)(2800 3175);
FORCEPROP 0 LAST SIG_NAME CLK_100M_PCH_SLOTX24_S2_DP
J 0
(1615 3185);
DISPLAY 0.617021 (1615 3185);
PAINT ORANGE (1615 3185);
WIRE 16 -1 (-1500 2775)(200 2775);
FORCEPROP 0 LAST SIG_NAME TP_SLOTX24_RSVD63
J 0
(-1375 2785);
DISPLAY 0.617021 (-1375 2785);
PAINT ORANGE (-1375 2785);
FORCEPROP 2 LASTPROP $XRERR UNIQUE?
J 0
(-1740 2775);
DISPLAY 0.638298 (-1740 2775);
PAINT MONO (-1740 2775);
DISPLAY INVISIBLE (-1740 2775);
WIRE 16 -1 (-500 2675)(200 2675);
WIRE 16 -1 (-500 2525)(200 2525);
WIRE 16 -1 (-700 2475)(200 2475);
WIRE 3 682 (-2425 3675)(-2825 3675);
WIRE 3 682 (-2825 3700)(-2825 3675);
WIRE 16 -1 (800 2575)(1300 2575);
WIRE 16 -1 (200 3025)(-700 3025);
WIRE 16 -1 (200 3075)(-500 3075);
WIRE 16 -1 (-1950 3175)(200 3175);
FORCEPROP 0 LAST SIG_NAME CLK_100M_PCH_SLOTX24_S3_DN
J 0
(-1885 3185);
DISPLAY 0.617021 (-1885 3185);
PAINT ORANGE (-1885 3185);
WIRE 16 -1 (200 3225)(-1950 3225);
FORCEPROP 0 LAST SIG_NAME CLK_100M_PCH_SLOTX24_S3_DP
J 0
(-1885 3235);
DISPLAY 0.617021 (-1885 3235);
PAINT ORANGE (-1885 3235);
WIRE 16 -1 (-1950 3375)(200 3375);
FORCEPROP 0 LAST SIG_NAME CLK_100M_PCH_SLOTX24_S0_DP
J 0
(-1885 3385);
DISPLAY 0.617021 (-1885 3385);
PAINT ORANGE (-1885 3385);
DOT 1 (-525 3825);
DOT 1 (-1900 4700);
DOT 1 (-1800 4250);
DOT 1 (-1800 4500);
DOT 1 (2350 3775);
DOT 1 (-100 3575);
DOT 1 (-350 4225);
DOT 1 (-350 4125);
DOT 1 (1050 2375);
DOT 1 (1375 4225);
DOT 1 (1375 4175);
DOT 1 (1375 4125);
DOT 1 (-3275 850);
DOT 1 (-3275 1575);
DOT 1 (-2875 400);
DOT 1 (-2875 1100);
DOT 1 (-2350 1550);
DOT 1 (-1950 1075);
DOT 1 (-100 2975);
DOT 1 (-350 4175);
DOT 1 (-350 4275);
DOT 1 (-350 4325);
DOT 1 (1050 2075);
DOT 1 (1050 3375);
DOT 1 (1050 3525);
DOT 1 (1050 3725);
DOT 1 (1375 4275);
DOT 1 (1375 4325);
DOT 1 (-100 2425);
DOT 1 (-100 2825);
DOT 1 (-100 1975);
DOT 1 (-100 2125);
DOT 1 (-100 2575);
DOT 1 (-100 1825);
DOT 1 (1050 2925);
DOT 1 (1050 2225);
DOT 1 (1050 1925);
DOT 1 (1050 1825);
DOT 1 (1050 2775);
DOT 1 (1550 2975);
DOT 1 (-600 3075);
DOT 1 (-100 2275);
DOT 1 (1050 2675);
DOT 1 (2750 3875);
DOT 1 (1050 3225);
DOT 1 (1050 2525);
DOT 1 (1050 3075);
DOT 1 (-100 3125);
DOT 1 (-100 3425);
DOT 1 (-100 2725);
DOT 1 (-100 3275);
DOT 1 (2800 3625);
DOT 1 (1600 3825);
FORCENOTE
TP FAB1 CHANGE CONNECTION 0309
(-3025 3725) 0;
DISPLAY LEFT (-3025 3725);
DISPLAY 1.021277 (-3025 3725);
PAINT RED (-3025 3725);
FORCENOTE
TP FAB1 PUT RES BACK 0310
(-1800 4625) 0;
DISPLAY LEFT (-1800 4625);
DISPLAY 1.021277 (-1800 4625);
PAINT RED (-1800 4625);
FORCENOTE
TP FAB1 DELETE RES (NO USE IE) 0118
(-1800 4700) 0;
DISPLAY LEFT (-1800 4700);
DISPLAY 1.021277 (-1800 4700);
PAINT RED (-1800 4700);
FORCENOTE
TP FAB1 CONNECT TO PCH 0227
(2875 3600) 0;
DISPLAY LEFT (2875 3600);
DISPLAY 1.021277 (2875 3600);
PAINT RED (2875 3600);
FORCENOTE
TP FAB1 RENAME 0307
(2325 2750) 0;
DISPLAY LEFT (2325 2750);
DISPLAY 1.021277 (2325 2750);
PAINT RED (2325 2750);
FORCENOTE
ROOM=IO_SLOT
(-3516 223) 0;
DISPLAY LEFT (-3516 223);
DISPLAY 1.021277 (-3516 223);
PAINT PURPLE (-3516 223);
FORCENOTE
TP FAB1 MODIFY PCIE TOPOLOGY AND FOR ROUTING SMOOTH CHANGE CLOCK PIN DEFINE 1116
(-1350 1400) 0;
DISPLAY LEFT (-1350 1400);
DISPLAY 1.021277 (-1350 1400);
PAINT RED (-1350 1400);
FORCENOTE
TP FAB1 RENAME 0307
(-1675 2625) 0;
DISPLAY LEFT (-1675 2625);
DISPLAY 1.021277 (-1675 2625);
PAINT RED (-1675 2625);
QUIT
